(kicad_sch
	(version 20250114)
	(generator "eeschema")
	(generator_version "9.0")
	(paper "A3")
	(title_block
		(title "RDIMM DDR5 Tester")
		(date "2026-05-21")
		(rev "2.2.0")
		(company "Antmicro")
		(comment 1 "www.antmicro.com")
		(comment 2 "Antmicro")
	)
	(text "Not populated"
		(exclude_from_sim no)
		(at 227.965 237.49 0)
		(effects
			(font
				(size 1.27 1.27)
			)
			(justify left bottom)
		)
	)
	(text "Subchannel B"
		(exclude_from_sim no)
		(at 130.81 44.45 0)
		(effects
			(font
				(size 2 2)
			)
			(justify left bottom)
		)
	)
	(text "DDR5 RDIMM connector"
		(exclude_from_sim no)
		(at 16.51 21.59 0)
		(effects
			(font
				(size 3 3)
				(thickness 0.5994)
				(bold yes)
			)
			(justify left bottom)
		)
	)
	(text "Power, address command and control"
		(exclude_from_sim no)
		(at 194.31 19.05 0)
		(effects
			(font
				(size 2 2)
				(thickness 0.4)
				(bold yes)
			)
			(justify left bottom)
		)
	)
	(text "HOT SWAP status LED"
		(exclude_from_sim no)
		(at 193.04 135.89 0)
		(effects
			(font
				(size 2 2)
				(thickness 0.4)
				(bold yes)
			)
			(justify left bottom)
		)
	)
	(text "HOT SWAP eject button"
		(exclude_from_sim no)
		(at 320.04 135.89 0)
		(effects
			(font
				(size 2 2)
				(thickness 0.4)
				(bold yes)
			)
			(justify left bottom)
		)
	)
	(text "Default 000"
		(exclude_from_sim no)
		(at 238.76 279.4 0)
		(effects
			(font
				(size 1.27 1.27)
			)
			(justify left bottom)
		)
	)
	(text "Plane decoupling"
		(exclude_from_sim no)
		(at 320.04 219.71 0)
		(effects
			(font
				(size 2 2)
				(thickness 0.4)
				(bold yes)
			)
			(justify left bottom)
		)
	)
	(text "~{DDR_PRESENCE}"
		(exclude_from_sim no)
		(at 195.072 240.792 0)
		(effects
			(font
				(size 1.27 1.27)
			)
			(justify left bottom)
		)
	)
	(text "Serial adress select"
		(exclude_from_sim no)
		(at 193.04 260.35 0)
		(effects
			(font
				(size 2 2)
				(thickness 0.4)
				(bold yes)
			)
			(justify left bottom)
		)
	)
	(text "Optional RC filter, tr=10ms"
		(exclude_from_sim no)
		(at 358.14 183.515 0)
		(effects
			(font
				(size 1.27 1.27)
			)
			(justify left bottom)
		)
	)
	(text "Subchannel A"
		(exclude_from_sim no)
		(at 44.45 44.45 0)
		(effects
			(font
				(size 2 2)
			)
			(justify left bottom)
		)
	)
	(text "0"
		(exclude_from_sim no)
		(at 217.932 240.538 0)
		(effects
			(font
				(size 1.27 1.27)
			)
			(justify left bottom)
		)
	)
	(text "1"
		(exclude_from_sim no)
		(at 232.918 240.538 0)
		(effects
			(font
				(size 1.27 1.27)
			)
			(justify left bottom)
		)
	)
	(text "Populated"
		(exclude_from_sim no)
		(at 212.09 237.49 0)
		(effects
			(font
				(size 1.27 1.27)
			)
			(justify left bottom)
		)
	)
	(text "RDIMM detect"
		(exclude_from_sim no)
		(at 194.31 219.71 0)
		(effects
			(font
				(size 2 2)
				(thickness 0.4)
				(bold yes)
			)
			(justify left bottom)
		)
	)
	(junction
		(at 226.06 60.96)
		(diameter 0)
		(color 0 0 0 0)
	)
	(junction
		(at 215.9 102.87)
		(diameter 0)
		(color 0 0 0 0)
	)
	(junction
		(at 248.92 82.55)
		(diameter 0)
		(color 0 0 0 0)
	)
	(junction
		(at 356.87 97.79)
		(diameter 0)
		(color 0 0 0 0)
	)
	(junction
		(at 347.98 168.91)
		(diameter 0)
		(color 0 0 0 0)
	)
	(junction
		(at 248.92 33.02)
		(diameter 0)
		(color 0 0 0 0)
	)
	(junction
		(at 226.06 41.91)
		(diameter 0)
		(color 0 0 0 0)
	)
	(junction
		(at 347.98 185.42)
		(diameter 0)
		(color 0 0 0 0)
	)
	(junction
		(at 226.06 110.49)
		(diameter 0)
		(color 0 0 0 0)
	)
	(junction
		(at 215.9 82.55)
		(diameter 0)
		(color 0 0 0 0)
	)
	(junction
		(at 226.06 92.71)
		(diameter 0)
		(color 0 0 0 0)
	)
	(junction
		(at 356.87 95.25)
		(diameter 0)
		(color 0 0 0 0)
	)
	(junction
		(at 271.78 234.95)
		(diameter 0)
		(color 0 0 0 0)
	)
	(junction
		(at 215.9 52.07)
		(diameter 0)
		(color 0 0 0 0)
	)
	(junction
		(at 215.9 33.02)
		(diameter 0)
		(color 0 0 0 0)
	)
	(junction
		(at 356.87 168.91)
		(diameter 0)
		(color 0 0 0 0)
	)
	(bus_entry
		(at 71.12 198.12)
		(size -2.54 -2.54)
		(stroke
			(width 0)
			(type default)
		)
	)
	(bus_entry
		(at 308.61 80.01)
		(size -2.54 -2.54)
		(stroke
			(width 0)
			(type default)
		)
	)
	(bus_entry
		(at 129.54 200.66)
		(size 2.54 -2.54)
		(stroke
			(width 0)
			(type default)
		)
	)
	(bus_entry
		(at 372.11 62.23)
		(size 2.54 -2.54)
		(stroke
			(width 0)
			(type default)
		)
	)
	(bus_entry
		(at 71.12 200.66)
		(size -2.54 -2.54)
		(stroke
			(width 0)
			(type default)
		)
	)
	(bus_entry
		(at 308.61 67.31)
		(size -2.54 -2.54)
		(stroke
			(width 0)
			(type default)
		)
	)
	(bus_entry
		(at 308.61 57.15)
		(size -2.54 -2.54)
		(stroke
			(width 0)
			(type default)
		)
	)
	(bus_entry
		(at 71.12 157.48)
		(size -2.54 -2.54)
		(stroke
			(width 0)
			(type default)
		)
	)
	(bus_entry
		(at 308.61 64.77)
		(size -2.54 -2.54)
		(stroke
			(width 0)
			(type default)
		)
	)
	(bus_entry
		(at 372.11 57.15)
		(size 2.54 -2.54)
		(stroke
			(width 0)
			(type default)
		)
	)
	(bus_entry
		(at 71.12 139.7)
		(size -2.54 -2.54)
		(stroke
			(width 0)
			(type default)
		)
	)
	(bus_entry
		(at 71.12 91.44)
		(size -2.54 -2.54)
		(stroke
			(width 0)
			(type default)
		)
	)
	(bus_entry
		(at 71.12 220.98)
		(size -2.54 -2.54)
		(stroke
			(width 0)
			(type default)
		)
	)
	(bus_entry
		(at 129.54 223.52)
		(size 2.54 -2.54)
		(stroke
			(width 0)
			(type default)
		)
	)
	(bus_entry
		(at 129.54 190.5)
		(size 2.54 -2.54)
		(stroke
			(width 0)
			(type default)
		)
	)
	(bus_entry
		(at 129.54 157.48)
		(size 2.54 -2.54)
		(stroke
			(width 0)
			(type default)
		)
	)
	(bus_entry
		(at 71.12 109.22)
		(size -2.54 -2.54)
		(stroke
			(width 0)
			(type default)
		)
	)
	(bus_entry
		(at 71.12 190.5)
		(size -2.54 -2.54)
		(stroke
			(width 0)
			(type default)
		)
	)
	(bus_entry
		(at 71.12 170.18)
		(size -2.54 -2.54)
		(stroke
			(width 0)
			(type default)
		)
	)
	(bus_entry
		(at 308.61 62.23)
		(size -2.54 -2.54)
		(stroke
			(width 0)
			(type default)
		)
	)
	(bus_entry
		(at 129.54 147.32)
		(size 2.54 -2.54)
		(stroke
			(width 0)
			(type default)
		)
	)
	(bus_entry
		(at 71.12 213.36)
		(size -2.54 -2.54)
		(stroke
			(width 0)
			(type default)
		)
	)
	(bus_entry
		(at 71.12 132.08)
		(size -2.54 -2.54)
		(stroke
			(width 0)
			(type default)
		)
	)
	(bus_entry
		(at 129.54 109.22)
		(size 2.54 -2.54)
		(stroke
			(width 0)
			(type default)
		)
	)
	(bus_entry
		(at 129.54 134.62)
		(size 2.54 -2.54)
		(stroke
			(width 0)
			(type default)
		)
	)
	(bus_entry
		(at 71.12 205.74)
		(size -2.54 -2.54)
		(stroke
			(width 0)
			(type default)
		)
	)
	(bus_entry
		(at 129.54 99.06)
		(size 2.54 -2.54)
		(stroke
			(width 0)
			(type default)
		)
	)
	(bus_entry
		(at 129.54 116.84)
		(size 2.54 -2.54)
		(stroke
			(width 0)
			(type default)
		)
	)
	(bus_entry
		(at 308.61 41.91)
		(size -2.54 -2.54)
		(stroke
			(width 0)
			(type default)
		)
	)
	(bus_entry
		(at 129.54 218.44)
		(size 2.54 -2.54)
		(stroke
			(width 0)
			(type default)
		)
	)
	(bus_entry
		(at 129.54 86.36)
		(size 2.54 -2.54)
		(stroke
			(width 0)
			(type default)
		)
	)
	(bus_entry
		(at 71.12 78.74)
		(size -2.54 -2.54)
		(stroke
			(width 0)
			(type default)
		)
	)
	(bus_entry
		(at 129.54 142.24)
		(size 2.54 -2.54)
		(stroke
			(width 0)
			(type default)
		)
	)
	(bus_entry
		(at 71.12 218.44)
		(size -2.54 -2.54)
		(stroke
			(width 0)
			(type default)
		)
	)
	(bus_entry
		(at 71.12 121.92)
		(size -2.54 -2.54)
		(stroke
			(width 0)
			(type default)
		)
	)
	(bus_entry
		(at 308.61 72.39)
		(size -2.54 -2.54)
		(stroke
			(width 0)
			(type default)
		)
	)
	(bus_entry
		(at 372.11 39.37)
		(size 2.54 -2.54)
		(stroke
			(width 0)
			(type default)
		)
	)
	(bus_entry
		(at 71.12 81.28)
		(size -2.54 -2.54)
		(stroke
			(width 0)
			(type default)
		)
	)
	(bus_entry
		(at 129.54 111.76)
		(size 2.54 -2.54)
		(stroke
			(width 0)
			(type default)
		)
	)
	(bus_entry
		(at 372.11 74.93)
		(size 2.54 -2.54)
		(stroke
			(width 0)
			(type default)
		)
	)
	(bus_entry
		(at 129.54 210.82)
		(size 2.54 -2.54)
		(stroke
			(width 0)
			(type default)
		)
	)
	(bus_entry
		(at 372.11 52.07)
		(size 2.54 -2.54)
		(stroke
			(width 0)
			(type default)
		)
	)
	(bus_entry
		(at 308.61 77.47)
		(size -2.54 -2.54)
		(stroke
			(width 0)
			(type default)
		)
	)
	(bus_entry
		(at 71.12 149.86)
		(size -2.54 -2.54)
		(stroke
			(width 0)
			(type default)
		)
	)
	(bus_entry
		(at 372.11 77.47)
		(size 2.54 -2.54)
		(stroke
			(width 0)
			(type default)
		)
	)
	(bus_entry
		(at 129.54 114.3)
		(size 2.54 -2.54)
		(stroke
			(width 0)
			(type default)
		)
	)
	(bus_entry
		(at 129.54 172.72)
		(size 2.54 -2.54)
		(stroke
			(width 0)
			(type default)
		)
	)
	(bus_entry
		(at 71.12 208.28)
		(size -2.54 -2.54)
		(stroke
			(width 0)
			(type default)
		)
	)
	(bus_entry
		(at 372.11 72.39)
		(size 2.54 -2.54)
		(stroke
			(width 0)
			(type default)
		)
	)
	(bus_entry
		(at 129.54 185.42)
		(size 2.54 -2.54)
		(stroke
			(width 0)
			(type default)
		)
	)
	(bus_entry
		(at 71.12 111.76)
		(size -2.54 -2.54)
		(stroke
			(width 0)
			(type default)
		)
	)
	(bus_entry
		(at 71.12 88.9)
		(size -2.54 -2.54)
		(stroke
			(width 0)
			(type default)
		)
	)
	(bus_entry
		(at 71.12 172.72)
		(size -2.54 -2.54)
		(stroke
			(width 0)
			(type default)
		)
	)
	(bus_entry
		(at 129.54 106.68)
		(size 2.54 -2.54)
		(stroke
			(width 0)
			(type default)
		)
	)
	(bus_entry
		(at 129.54 63.5)
		(size 2.54 -2.54)
		(stroke
			(width 0)
			(type default)
		)
	)
	(bus_entry
		(at 71.12 180.34)
		(size -2.54 -2.54)
		(stroke
			(width 0)
			(type default)
		)
	)
	(bus_entry
		(at 129.54 187.96)
		(size 2.54 -2.54)
		(stroke
			(width 0)
			(type default)
		)
	)
	(bus_entry
		(at 71.12 134.62)
		(size -2.54 -2.54)
		(stroke
			(width 0)
			(type default)
		)
	)
	(bus_entry
		(at 71.12 106.68)
		(size -2.54 -2.54)
		(stroke
			(width 0)
			(type default)
		)
	)
	(bus_entry
		(at 129.54 81.28)
		(size 2.54 -2.54)
		(stroke
			(width 0)
			(type default)
		)
	)
	(bus_entry
		(at 71.12 182.88)
		(size -2.54 -2.54)
		(stroke
			(width 0)
			(type default)
		)
	)
	(bus_entry
		(at 129.54 175.26)
		(size 2.54 -2.54)
		(stroke
			(width 0)
			(type default)
		)
	)
	(bus_entry
		(at 129.54 198.12)
		(size 2.54 -2.54)
		(stroke
			(width 0)
			(type default)
		)
	)
	(bus_entry
		(at 129.54 144.78)
		(size 2.54 -2.54)
		(stroke
			(width 0)
			(type default)
		)
	)
	(bus_entry
		(at 71.12 66.04)
		(size -2.54 -2.54)
		(stroke
			(width 0)
			(type default)
		)
	)
	(bus_entry
		(at 306.07 49.53)
		(size 2.54 2.54)
		(stroke
			(width 0)
			(type default)
		)
	)
	(bus_entry
		(at 71.12 101.6)
		(size -2.54 -2.54)
		(stroke
			(width 0)
			(type default)
		)
	)
	(bus_entry
		(at 71.12 165.1)
		(size -2.54 -2.54)
		(stroke
			(width 0)
			(type default)
		)
	)
	(bus_entry
		(at 71.12 129.54)
		(size -2.54 -2.54)
		(stroke
			(width 0)
			(type default)
		)
	)
	(bus_entry
		(at 372.11 64.77)
		(size 2.54 -2.54)
		(stroke
			(width 0)
			(type default)
		)
	)
	(bus_entry
		(at 129.54 121.92)
		(size 2.54 -2.54)
		(stroke
			(width 0)
			(type default)
		)
	)
	(bus_entry
		(at 308.61 74.93)
		(size -2.54 -2.54)
		(stroke
			(width 0)
			(type default)
		)
	)
	(bus_entry
		(at 129.54 68.58)
		(size 2.54 -2.54)
		(stroke
			(width 0)
			(type default)
		)
	)
	(bus_entry
		(at 71.12 154.94)
		(size -2.54 -2.54)
		(stroke
			(width 0)
			(type default)
		)
	)
	(bus_entry
		(at 71.12 195.58)
		(size -2.54 -2.54)
		(stroke
			(width 0)
			(type default)
		)
	)
	(bus_entry
		(at 129.54 124.46)
		(size 2.54 -2.54)
		(stroke
			(width 0)
			(type default)
		)
	)
	(bus_entry
		(at 372.11 49.53)
		(size 2.54 -2.54)
		(stroke
			(width 0)
			(type default)
		)
	)
	(bus_entry
		(at 71.12 63.5)
		(size -2.54 -2.54)
		(stroke
			(width 0)
			(type default)
		)
	)
	(bus_entry
		(at 129.54 132.08)
		(size 2.54 -2.54)
		(stroke
			(width 0)
			(type default)
		)
	)
	(bus_entry
		(at 71.12 119.38)
		(size -2.54 -2.54)
		(stroke
			(width 0)
			(type default)
		)
	)
	(bus_entry
		(at 372.11 67.31)
		(size 2.54 -2.54)
		(stroke
			(width 0)
			(type default)
		)
	)
	(bus_entry
		(at 129.54 165.1)
		(size 2.54 -2.54)
		(stroke
			(width 0)
			(type default)
		)
	)
	(bus_entry
		(at 71.12 68.58)
		(size -2.54 -2.54)
		(stroke
			(width 0)
			(type default)
		)
	)
	(bus_entry
		(at 129.54 167.64)
		(size 2.54 -2.54)
		(stroke
			(width 0)
			(type default)
		)
	)
	(bus_entry
		(at 129.54 205.74)
		(size 2.54 -2.54)
		(stroke
			(width 0)
			(type default)
		)
	)
	(bus_entry
		(at 129.54 101.6)
		(size 2.54 -2.54)
		(stroke
			(width 0)
			(type default)
		)
	)
	(bus_entry
		(at 71.12 147.32)
		(size -2.54 -2.54)
		(stroke
			(width 0)
			(type default)
		)
	)
	(bus_entry
		(at 71.12 116.84)
		(size -2.54 -2.54)
		(stroke
			(width 0)
			(type default)
		)
	)
	(bus_entry
		(at 71.12 86.36)
		(size -2.54 -2.54)
		(stroke
			(width 0)
			(type default)
		)
	)
	(bus_entry
		(at 372.11 59.69)
		(size 2.54 -2.54)
		(stroke
			(width 0)
			(type default)
		)
	)
	(bus_entry
		(at 129.54 154.94)
		(size 2.54 -2.54)
		(stroke
			(width 0)
			(type default)
		)
	)
	(bus_entry
		(at 129.54 104.14)
		(size 2.54 -2.54)
		(stroke
			(width 0)
			(type default)
		)
	)
	(bus_entry
		(at 129.54 78.74)
		(size 2.54 -2.54)
		(stroke
			(width 0)
			(type default)
		)
	)
	(bus_entry
		(at 129.54 170.18)
		(size 2.54 -2.54)
		(stroke
			(width 0)
			(type default)
		)
	)
	(bus_entry
		(at 129.54 66.04)
		(size 2.54 -2.54)
		(stroke
			(width 0)
			(type default)
		)
	)
	(bus_entry
		(at 372.11 69.85)
		(size 2.54 -2.54)
		(stroke
			(width 0)
			(type default)
		)
	)
	(bus_entry
		(at 71.12 83.82)
		(size -2.54 -2.54)
		(stroke
			(width 0)
			(type default)
		)
	)
	(bus_entry
		(at 308.61 69.85)
		(size -2.54 -2.54)
		(stroke
			(width 0)
			(type default)
		)
	)
	(bus_entry
		(at 71.12 162.56)
		(size -2.54 -2.54)
		(stroke
			(width 0)
			(type default)
		)
	)
	(bus_entry
		(at 71.12 185.42)
		(size -2.54 -2.54)
		(stroke
			(width 0)
			(type default)
		)
	)
	(bus_entry
		(at 129.54 76.2)
		(size 2.54 -2.54)
		(stroke
			(width 0)
			(type default)
		)
	)
	(bus_entry
		(at 71.12 210.82)
		(size -2.54 -2.54)
		(stroke
			(width 0)
			(type default)
		)
	)
	(bus_entry
		(at 129.54 83.82)
		(size 2.54 -2.54)
		(stroke
			(width 0)
			(type default)
		)
	)
	(bus_entry
		(at 129.54 71.12)
		(size 2.54 -2.54)
		(stroke
			(width 0)
			(type default)
		)
	)
	(bus_entry
		(at 129.54 119.38)
		(size 2.54 -2.54)
		(stroke
			(width 0)
			(type default)
		)
	)
	(bus_entry
		(at 372.11 46.99)
		(size 2.54 -2.54)
		(stroke
			(width 0)
			(type default)
		)
	)
	(bus_entry
		(at 129.54 91.44)
		(size 2.54 -2.54)
		(stroke
			(width 0)
			(type default)
		)
	)
	(bus_entry
		(at 129.54 215.9)
		(size 2.54 -2.54)
		(stroke
			(width 0)
			(type default)
		)
	)
	(bus_entry
		(at 71.12 71.12)
		(size -2.54 -2.54)
		(stroke
			(width 0)
			(type default)
		)
	)
	(bus_entry
		(at 71.12 124.46)
		(size -2.54 -2.54)
		(stroke
			(width 0)
			(type default)
		)
	)
	(bus_entry
		(at 71.12 104.14)
		(size -2.54 -2.54)
		(stroke
			(width 0)
			(type default)
		)
	)
	(bus_entry
		(at 129.54 177.8)
		(size 2.54 -2.54)
		(stroke
			(width 0)
			(type default)
		)
	)
	(bus_entry
		(at 306.07 46.99)
		(size 2.54 2.54)
		(stroke
			(width 0)
			(type default)
		)
	)
	(bus_entry
		(at 129.54 180.34)
		(size 2.54 -2.54)
		(stroke
			(width 0)
			(type default)
		)
	)
	(bus_entry
		(at 71.12 73.66)
		(size -2.54 -2.54)
		(stroke
			(width 0)
			(type default)
		)
	)
	(bus_entry
		(at 71.12 152.4)
		(size -2.54 -2.54)
		(stroke
			(width 0)
			(type default)
		)
	)
	(bus_entry
		(at 129.54 137.16)
		(size 2.54 -2.54)
		(stroke
			(width 0)
			(type default)
		)
	)
	(bus_entry
		(at 129.54 96.52)
		(size 2.54 -2.54)
		(stroke
			(width 0)
			(type default)
		)
	)
	(bus_entry
		(at 71.12 137.16)
		(size -2.54 -2.54)
		(stroke
			(width 0)
			(type default)
		)
	)
	(bus_entry
		(at 129.54 139.7)
		(size 2.54 -2.54)
		(stroke
			(width 0)
			(type default)
		)
	)
	(bus_entry
		(at 71.12 177.8)
		(size -2.54 -2.54)
		(stroke
			(width 0)
			(type default)
		)
	)
	(bus_entry
		(at 71.12 167.64)
		(size -2.54 -2.54)
		(stroke
			(width 0)
			(type default)
		)
	)
	(bus_entry
		(at 129.54 152.4)
		(size 2.54 -2.54)
		(stroke
			(width 0)
			(type default)
		)
	)
	(bus_entry
		(at 71.12 144.78)
		(size -2.54 -2.54)
		(stroke
			(width 0)
			(type default)
		)
	)
	(bus_entry
		(at 308.61 59.69)
		(size -2.54 -2.54)
		(stroke
			(width 0)
			(type default)
		)
	)
	(bus_entry
		(at 129.54 220.98)
		(size 2.54 -2.54)
		(stroke
			(width 0)
			(type default)
		)
	)
	(bus_entry
		(at 71.12 99.06)
		(size -2.54 -2.54)
		(stroke
			(width 0)
			(type default)
		)
	)
	(bus_entry
		(at 71.12 203.2)
		(size -2.54 -2.54)
		(stroke
			(width 0)
			(type default)
		)
	)
	(bus_entry
		(at 71.12 114.3)
		(size -2.54 -2.54)
		(stroke
			(width 0)
			(type default)
		)
	)
	(bus_entry
		(at 129.54 208.28)
		(size 2.54 -2.54)
		(stroke
			(width 0)
			(type default)
		)
	)
	(bus_entry
		(at 308.61 46.99)
		(size -2.54 -2.54)
		(stroke
			(width 0)
			(type default)
		)
	)
	(bus_entry
		(at 372.11 80.01)
		(size 2.54 -2.54)
		(stroke
			(width 0)
			(type default)
		)
	)
	(bus_entry
		(at 129.54 88.9)
		(size 2.54 -2.54)
		(stroke
			(width 0)
			(type default)
		)
	)
	(bus_entry
		(at 71.12 223.52)
		(size -2.54 -2.54)
		(stroke
			(width 0)
			(type default)
		)
	)
	(bus_entry
		(at 71.12 96.52)
		(size -2.54 -2.54)
		(stroke
			(width 0)
			(type default)
		)
	)
	(bus_entry
		(at 129.54 129.54)
		(size 2.54 -2.54)
		(stroke
			(width 0)
			(type default)
		)
	)
	(bus_entry
		(at 129.54 213.36)
		(size 2.54 -2.54)
		(stroke
			(width 0)
			(type default)
		)
	)
	(bus_entry
		(at 129.54 203.2)
		(size 2.54 -2.54)
		(stroke
			(width 0)
			(type default)
		)
	)
	(bus_entry
		(at 129.54 162.56)
		(size 2.54 -2.54)
		(stroke
			(width 0)
			(type default)
		)
	)
	(bus_entry
		(at 71.12 215.9)
		(size -2.54 -2.54)
		(stroke
			(width 0)
			(type default)
		)
	)
	(bus_entry
		(at 129.54 195.58)
		(size 2.54 -2.54)
		(stroke
			(width 0)
			(type default)
		)
	)
	(bus_entry
		(at 129.54 182.88)
		(size 2.54 -2.54)
		(stroke
			(width 0)
			(type default)
		)
	)
	(bus_entry
		(at 71.12 175.26)
		(size -2.54 -2.54)
		(stroke
			(width 0)
			(type default)
		)
	)
	(bus_entry
		(at 372.11 41.91)
		(size 2.54 -2.54)
		(stroke
			(width 0)
			(type default)
		)
	)
	(bus_entry
		(at 129.54 149.86)
		(size 2.54 -2.54)
		(stroke
			(width 0)
			(type default)
		)
	)
	(bus_entry
		(at 129.54 73.66)
		(size 2.54 -2.54)
		(stroke
			(width 0)
			(type default)
		)
	)
	(bus_entry
		(at 71.12 187.96)
		(size -2.54 -2.54)
		(stroke
			(width 0)
			(type default)
		)
	)
	(bus_entry
		(at 71.12 142.24)
		(size -2.54 -2.54)
		(stroke
			(width 0)
			(type default)
		)
	)
	(bus_entry
		(at 71.12 76.2)
		(size -2.54 -2.54)
		(stroke
			(width 0)
			(type default)
		)
	)
	(wire
		(pts
			(xy 115.57 170.18) (xy 129.54 170.18)
		)
		(stroke
			(width 0)
			(type default)
		)
	)
	(polyline
		(pts
			(xy 210.82 234.95) (xy 210.82 241.3)
		)
		(stroke
			(width 0)
			(type default)
		)
	)
	(wire
		(pts
			(xy 115.57 63.5) (xy 129.54 63.5)
		)
		(stroke
			(width 0)
			(type default)
		)
	)
	(wire
		(pts
			(xy 226.06 41.91) (xy 226.06 40.64)
		)
		(stroke
			(width 0)
			(type default)
		)
	)
	(wire
		(pts
			(xy 71.12 101.6) (xy 85.09 101.6)
		)
		(stroke
			(width 0)
			(type default)
		)
	)
	(wire
		(pts
			(xy 71.12 185.42) (xy 85.09 185.42)
		)
		(stroke
			(width 0)
			(type default)
		)
	)
	(wire
		(pts
			(xy 251.46 166.37) (xy 251.46 187.96)
		)
		(stroke
			(width 0)
			(type default)
		)
	)
	(wire
		(pts
			(xy 71.12 106.68) (xy 85.09 106.68)
		)
		(stroke
			(width 0)
			(type default)
		)
	)
	(wire
		(pts
			(xy 71.12 170.18) (xy 85.09 170.18)
		)
		(stroke
			(width 0)
			(type default)
		)
	)
	(bus
		(pts
			(xy 132.08 78.74) (xy 132.08 81.28)
		)
		(stroke
			(width 0)
			(type default)
		)
	)
	(wire
		(pts
			(xy 115.57 198.12) (xy 129.54 198.12)
		)
		(stroke
			(width 0)
			(type default)
		)
	)
	(wire
		(pts
			(xy 248.92 82.55) (xy 248.92 85.09)
		)
		(stroke
			(width 0)
			(type default)
		)
	)
	(wire
		(pts
			(xy 215.9 60.96) (xy 226.06 60.96)
		)
		(stroke
			(width 0)
			(type default)
		)
	)
	(bus
		(pts
			(xy 132.08 139.7) (xy 132.08 142.24)
		)
		(stroke
			(width 0)
			(type default)
		)
	)
	(bus
		(pts
			(xy 68.58 152.4) (xy 68.58 154.94)
		)
		(stroke
			(width 0)
			(type default)
		)
	)
	(wire
		(pts
			(xy 71.12 182.88) (xy 85.09 182.88)
		)
		(stroke
			(width 0)
			(type default)
		)
	)
	(wire
		(pts
			(xy 71.12 99.06) (xy 85.09 99.06)
		)
		(stroke
			(width 0)
			(type default)
		)
	)
	(bus
		(pts
			(xy 68.58 215.9) (xy 68.58 218.44)
		)
		(stroke
			(width 0)
			(type default)
		)
	)
	(wire
		(pts
			(xy 271.78 226.06) (xy 271.78 223.52)
		)
		(stroke
			(width 0)
			(type default)
		)
	)
	(wire
		(pts
			(xy 271.78 109.22) (xy 281.94 109.22)
		)
		(stroke
			(width 0)
			(type default)
		)
	)
	(bus
		(pts
			(xy 132.08 96.52) (xy 132.08 99.06)
		)
		(stroke
			(width 0)
			(type default)
		)
	)
	(wire
		(pts
			(xy 271.78 92.71) (xy 271.78 93.98)
		)
		(stroke
			(width 0)
			(type default)
		)
	)
	(wire
		(pts
			(xy 71.12 129.54) (xy 85.09 129.54)
		)
		(stroke
			(width 0)
			(type default)
		)
	)
	(wire
		(pts
			(xy 220.98 154.94) (xy 226.06 154.94)
		)
		(stroke
			(width 0)
			(type default)
		)
	)
	(wire
		(pts
			(xy 115.57 104.14) (xy 129.54 104.14)
		)
		(stroke
			(width 0)
			(type default)
		)
	)
	(bus
		(pts
			(xy 68.58 185.42) (xy 68.58 187.96)
		)
		(stroke
			(width 0)
			(type default)
		)
	)
	(wire
		(pts
			(xy 71.12 71.12) (xy 85.09 71.12)
		)
		(stroke
			(width 0)
			(type default)
		)
	)
	(bus
		(pts
			(xy 68.58 160.02) (xy 68.58 162.56)
		)
		(stroke
			(width 0)
			(type default)
		)
	)
	(wire
		(pts
			(xy 71.12 83.82) (xy 85.09 83.82)
		)
		(stroke
			(width 0)
			(type default)
		)
	)
	(bus
		(pts
			(xy 68.58 137.16) (xy 68.58 139.7)
		)
		(stroke
			(width 0)
			(type default)
		)
	)
	(wire
		(pts
			(xy 354.33 80.01) (xy 372.11 80.01)
		)
		(stroke
			(width 0)
			(type default)
		)
	)
	(wire
		(pts
			(xy 271.78 234.95) (xy 271.78 238.76)
		)
		(stroke
			(width 0)
			(type default)
		)
	)
	(wire
		(pts
			(xy 347.98 168.91) (xy 356.87 168.91)
		)
		(stroke
			(width 0)
			(type default)
		)
	)
	(wire
		(pts
			(xy 214.63 52.07) (xy 215.9 52.07)
		)
		(stroke
			(width 0)
			(type default)
		)
	)
	(bus
		(pts
			(xy 68.58 142.24) (xy 68.58 144.78)
		)
		(stroke
			(width 0)
			(type default)
		)
	)
	(wire
		(pts
			(xy 71.12 132.08) (xy 85.09 132.08)
		)
		(stroke
			(width 0)
			(type default)
		)
	)
	(wire
		(pts
			(xy 215.9 33.02) (xy 222.25 33.02)
		)
		(stroke
			(width 0)
			(type default)
		)
	)
	(bus
		(pts
			(xy 68.58 175.26) (xy 68.58 177.8)
		)
		(stroke
			(width 0)
			(type default)
		)
	)
	(wire
		(pts
			(xy 115.57 101.6) (xy 129.54 101.6)
		)
		(stroke
			(width 0)
			(type default)
		)
	)
	(wire
		(pts
			(xy 275.59 234.95) (xy 271.78 234.95)
		)
		(stroke
			(width 0)
			(type default)
		)
	)
	(wire
		(pts
			(xy 71.12 111.76) (xy 85.09 111.76)
		)
		(stroke
			(width 0)
			(type default)
		)
	)
	(bus
		(pts
			(xy 132.08 63.5) (xy 132.08 66.04)
		)
		(stroke
			(width 0)
			(type default)
		)
	)
	(wire
		(pts
			(xy 115.57 91.44) (xy 129.54 91.44)
		)
		(stroke
			(width 0)
			(type default)
		)
	)
	(wire
		(pts
			(xy 115.57 167.64) (xy 129.54 167.64)
		)
		(stroke
			(width 0)
			(type default)
		)
	)
	(bus
		(pts
			(xy 68.58 68.58) (xy 68.58 71.12)
		)
		(stroke
			(width 0)
			(type default)
		)
	)
	(wire
		(pts
			(xy 71.12 180.34) (xy 85.09 180.34)
		)
		(stroke
			(width 0)
			(type default)
		)
	)
	(bus
		(pts
			(xy 132.08 127) (xy 132.08 129.54)
		)
		(stroke
			(width 0)
			(type default)
		)
	)
	(bus
		(pts
			(xy 68.58 111.76) (xy 68.58 114.3)
		)
		(stroke
			(width 0)
			(type default)
		)
	)
	(wire
		(pts
			(xy 248.92 90.17) (xy 248.92 91.44)
		)
		(stroke
			(width 0)
			(type default)
		)
	)
	(wire
		(pts
			(xy 271.78 92.71) (xy 281.94 92.71)
		)
		(stroke
			(width 0)
			(type default)
		)
	)
	(bus
		(pts
			(xy 68.58 106.68) (xy 68.58 109.22)
		)
		(stroke
			(width 0)
			(type default)
		)
	)
	(wire
		(pts
			(xy 364.49 240.03) (xy 364.49 238.76)
		)
		(stroke
			(width 0)
			(type default)
		)
	)
	(bus
		(pts
			(xy 132.08 175.26) (xy 132.08 177.8)
		)
		(stroke
			(width 0)
			(type default)
		)
	)
	(wire
		(pts
			(xy 71.12 213.36) (xy 85.09 213.36)
		)
		(stroke
			(width 0)
			(type default)
		)
	)
	(bus
		(pts
			(xy 68.58 162.56) (xy 68.58 165.1)
		)
		(stroke
			(width 0)
			(type default)
		)
	)
	(bus
		(pts
			(xy 374.65 72.39) (xy 374.65 74.93)
		)
		(stroke
			(width 0)
			(type default)
		)
	)
	(bus
		(pts
			(xy 132.08 121.92) (xy 132.08 127)
		)
		(stroke
			(width 0)
			(type default)
		)
	)
	(wire
		(pts
			(xy 115.57 106.68) (xy 129.54 106.68)
		)
		(stroke
			(width 0)
			(type default)
		)
	)
	(wire
		(pts
			(xy 115.57 177.8) (xy 129.54 177.8)
		)
		(stroke
			(width 0)
			(type default)
		)
	)
	(wire
		(pts
			(xy 356.87 168.91) (xy 356.87 175.26)
		)
		(stroke
			(width 0)
			(type default)
		)
	)
	(bus
		(pts
			(xy 306.07 59.69) (xy 306.07 62.23)
		)
		(stroke
			(width 0)
			(type default)
		)
	)
	(bus
		(pts
			(xy 68.58 73.66) (xy 68.58 76.2)
		)
		(stroke
			(width 0)
			(type default)
		)
	)
	(wire
		(pts
			(xy 71.12 124.46) (xy 85.09 124.46)
		)
		(stroke
			(width 0)
			(type default)
		)
	)
	(wire
		(pts
			(xy 288.29 204.47) (xy 288.29 180.34)
		)
		(stroke
			(width 0)
			(type default)
		)
	)
	(wire
		(pts
			(xy 115.57 157.48) (xy 129.54 157.48)
		)
		(stroke
			(width 0)
			(type default)
		)
	)
	(bus
		(pts
			(xy 374.65 54.61) (xy 374.65 57.15)
		)
		(stroke
			(width 0)
			(type default)
		)
	)
	(wire
		(pts
			(xy 115.57 180.34) (xy 129.54 180.34)
		)
		(stroke
			(width 0)
			(type default)
		)
	)
	(wire
		(pts
			(xy 71.12 215.9) (xy 85.09 215.9)
		)
		(stroke
			(width 0)
			(type default)
		)
	)
	(wire
		(pts
			(xy 71.12 91.44) (xy 85.09 91.44)
		)
		(stroke
			(width 0)
			(type default)
		)
	)
	(wire
		(pts
			(xy 243.84 270.51) (xy 243.84 271.78)
		)
		(stroke
			(width 0)
			(type default)
		)
	)
	(wire
		(pts
			(xy 242.57 176.53) (xy 280.67 176.53)
		)
		(stroke
			(width 0)
			(type default)
		)
	)
	(bus
		(pts
			(xy 68.58 86.36) (xy 68.58 88.9)
		)
		(stroke
			(width 0)
			(type default)
		)
	)
	(wire
		(pts
			(xy 115.57 218.44) (xy 129.54 218.44)
		)
		(stroke
			(width 0)
			(type default)
		)
	)
	(wire
		(pts
			(xy 322.58 92.71) (xy 323.85 92.71)
		)
		(stroke
			(width 0)
			(type default)
		)
	)
	(wire
		(pts
			(xy 347.98 185.42) (xy 347.98 204.47)
		)
		(stroke
			(width 0)
			(type default)
		)
	)
	(polyline
		(pts
			(xy 190.5 11.43) (xy 190.5 25.4)
		)
		(stroke
			(width 0)
			(type default)
		)
	)
	(wire
		(pts
			(xy 71.12 104.14) (xy 85.09 104.14)
		)
		(stroke
			(width 0)
			(type default)
		)
	)
	(wire
		(pts
			(xy 226.06 111.76) (xy 226.06 110.49)
		)
		(stroke
			(width 0)
			(type default)
		)
	)
	(wire
		(pts
			(xy 214.63 33.02) (xy 215.9 33.02)
		)
		(stroke
			(width 0)
			(type default)
		)
	)
	(wire
		(pts
			(xy 356.87 97.79) (xy 354.33 97.79)
		)
		(stroke
			(width 0)
			(type default)
		)
	)
	(wire
		(pts
			(xy 115.57 119.38) (xy 129.54 119.38)
		)
		(stroke
			(width 0)
			(type default)
		)
	)
	(bus
		(pts
			(xy 374.65 43.18) (xy 374.65 44.45)
		)
		(stroke
			(width 0)
			(type default)
		)
	)
	(bus
		(pts
			(xy 68.58 180.34) (xy 68.58 182.88)
		)
		(stroke
			(width 0)
			(type default)
		)
	)
	(bus
		(pts
			(xy 68.58 132.08) (xy 68.58 134.62)
		)
		(stroke
			(width 0)
			(type default)
		)
	)
	(bus
		(pts
			(xy 132.08 60.96) (xy 132.08 63.5)
		)
		(stroke
			(width 0)
			(type default)
		)
	)
	(wire
		(pts
			(xy 115.57 187.96) (xy 129.54 187.96)
		)
		(stroke
			(width 0)
			(type default)
		)
	)
	(bus
		(pts
			(xy 132.08 132.08) (xy 132.08 134.62)
		)
		(stroke
			(width 0)
			(type default)
		)
	)
	(wire
		(pts
			(xy 71.12 109.22) (xy 85.09 109.22)
		)
		(stroke
			(width 0)
			(type default)
		)
	)
	(polyline
		(pts
			(xy 190.5 213.36) (xy 317.5 213.36)
		)
		(stroke
			(width 0)
			(type default)
		)
	)
	(wire
		(pts
			(xy 271.78 243.84) (xy 271.78 245.11)
		)
		(stroke
			(width 0)
			(type default)
		)
	)
	(wire
		(pts
			(xy 71.12 134.62) (xy 85.09 134.62)
		)
		(stroke
			(width 0)
			(type default)
		)
	)
	(wire
		(pts
			(xy 71.12 86.36) (xy 85.09 86.36)
		)
		(stroke
			(width 0)
			(type default)
		)
	)
	(wire
		(pts
			(xy 115.57 185.42) (xy 129.54 185.42)
		)
		(stroke
			(width 0)
			(type default)
		)
	)
	(wire
		(pts
			(xy 226.06 60.96) (xy 226.06 55.88)
		)
		(stroke
			(width 0)
			(type default)
		)
	)
	(bus
		(pts
			(xy 68.58 119.38) (xy 68.58 121.92)
		)
		(stroke
			(width 0)
			(type default)
		)
	)
	(wire
		(pts
			(xy 115.57 78.74) (xy 129.54 78.74)
		)
		(stroke
			(width 0)
			(type default)
		)
	)
	(wire
		(pts
			(xy 71.12 152.4) (xy 85.09 152.4)
		)
		(stroke
			(width 0)
			(type default)
		)
	)
	(wire
		(pts
			(xy 115.57 76.2) (xy 129.54 76.2)
		)
		(stroke
			(width 0)
			(type default)
		)
	)
	(wire
		(pts
			(xy 281.94 92.71) (xy 281.94 93.98)
		)
		(stroke
			(width 0)
			(type default)
		)
	)
	(bus
		(pts
			(xy 306.07 53.34) (xy 306.07 54.61)
		)
		(stroke
			(width 0)
			(type default)
		)
	)
	(bus
		(pts
			(xy 299.72 36.83) (xy 304.8 36.83)
		)
		(stroke
			(width 0)
			(type default)
		)
	)
	(wire
		(pts
			(xy 115.57 83.82) (xy 129.54 83.82)
		)
		(stroke
			(width 0)
			(type default)
		)
	)
	(bus
		(pts
			(xy 68.58 101.6) (xy 68.58 104.14)
		)
		(stroke
			(width 0)
			(type default)
		)
	)
	(wire
		(pts
			(xy 71.12 116.84) (xy 85.09 116.84)
		)
		(stroke
			(width 0)
			(type default)
		)
	)
	(bus
		(pts
			(xy 132.08 210.82) (xy 132.08 213.36)
		)
		(stroke
			(width 0)
			(type default)
		)
	)
	(wire
		(pts
			(xy 354.33 69.85) (xy 372.11 69.85)
		)
		(stroke
			(width 0)
			(type default)
		)
	)
	(wire
		(pts
			(xy 356.87 92.71) (xy 356.87 95.25)
		)
		(stroke
			(width 0)
			(type default)
		)
	)
	(wire
		(pts
			(xy 356.87 168.91) (xy 364.49 168.91)
		)
		(stroke
			(width 0)
			(type default)
		)
	)
	(bus
		(pts
			(xy 68.58 193.04) (xy 68.58 195.58)
		)
		(stroke
			(width 0)
			(type default)
		)
	)
	(bus
		(pts
			(xy 132.08 101.6) (xy 132.08 104.14)
		)
		(stroke
			(width 0)
			(type default)
		)
	)
	(wire
		(pts
			(xy 115.57 111.76) (xy 129.54 111.76)
		)
		(stroke
			(width 0)
			(type default)
		)
	)
	(bus
		(pts
			(xy 374.65 69.85) (xy 374.65 72.39)
		)
		(stroke
			(width 0)
			(type default)
		)
	)
	(wire
		(pts
			(xy 254 234.95) (xy 271.78 234.95)
		)
		(stroke
			(width 0)
			(type default)
		)
	)
	(bus
		(pts
			(xy 68.58 96.52) (xy 68.58 99.06)
		)
		(stroke
			(width 0)
			(type default)
		)
	)
	(bus
		(pts
			(xy 306.07 53.34) (xy 304.8 52.07)
		)
		(stroke
			(width 0)
			(type default)
		)
	)
	(wire
		(pts
			(xy 71.12 76.2) (xy 85.09 76.2)
		)
		(stroke
			(width 0)
			(type default)
		)
	)
	(wire
		(pts
			(xy 215.9 82.55) (xy 222.25 82.55)
		)
		(stroke
			(width 0)
			(type default)
		)
	)
	(wire
		(pts
			(xy 347.98 168.91) (xy 345.44 168.91)
		)
		(stroke
			(width 0)
			(type default)
		)
	)
	(bus
		(pts
			(xy 68.58 71.12) (xy 68.58 73.66)
		)
		(stroke
			(width 0)
			(type default)
		)
	)
	(wire
		(pts
			(xy 71.12 177.8) (xy 85.09 177.8)
		)
		(stroke
			(width 0)
			(type default)
		)
	)
	(bus
		(pts
			(xy 68.58 218.44) (xy 68.58 220.98)
		)
		(stroke
			(width 0)
			(type default)
		)
	)
	(wire
		(pts
			(xy 308.61 41.91) (xy 323.85 41.91)
		)
		(stroke
			(width 0)
			(type default)
		)
	)
	(bus
		(pts
			(xy 68.58 177.8) (xy 68.58 180.34)
		)
		(stroke
			(width 0)
			(type default)
		)
	)
	(wire
		(pts
			(xy 308.61 62.23) (xy 323.85 62.23)
		)
		(stroke
			(width 0)
			(type default)
		)
	)
	(wire
		(pts
			(xy 71.12 200.66) (xy 85.09 200.66)
		)
		(stroke
			(width 0)
			(type default)
		)
	)
	(wire
		(pts
			(xy 115.57 162.56) (xy 129.54 162.56)
		)
		(stroke
			(width 0)
			(type default)
		)
	)
	(wire
		(pts
			(xy 115.57 203.2) (xy 129.54 203.2)
		)
		(stroke
			(width 0)
			(type default)
		)
	)
	(wire
		(pts
			(xy 115.57 147.32) (xy 129.54 147.32)
		)
		(stroke
			(width 0)
			(type default)
		)
	)
	(wire
		(pts
			(xy 354.33 52.07) (xy 372.11 52.07)
		)
		(stroke
			(width 0)
			(type default)
		)
	)
	(wire
		(pts
			(xy 71.12 190.5) (xy 85.09 190.5)
		)
		(stroke
			(width 0)
			(type default)
		)
	)
	(bus
		(pts
			(xy 132.08 129.54) (xy 132.08 132.08)
		)
		(stroke
			(width 0)
			(type default)
		)
	)
	(polyline
		(pts
			(xy 190.5 254) (xy 241.3 254)
		)
		(stroke
			(width 0)
			(type default)
		)
	)
	(bus
		(pts
			(xy 132.08 203.2) (xy 132.08 205.74)
		)
		(stroke
			(width 0)
			(type default)
		)
	)
	(wire
		(pts
			(xy 347.98 185.42) (xy 356.87 185.42)
		)
		(stroke
			(width 0)
			(type default)
		)
	)
	(bus
		(pts
			(xy 68.58 52.07) (xy 68.58 60.96)
		)
		(stroke
			(width 0)
			(type default)
		)
	)
	(bus
		(pts
			(xy 132.08 213.36) (xy 132.08 215.9)
		)
		(stroke
			(width 0)
			(type default)
		)
	)
	(wire
		(pts
			(xy 215.9 109.22) (xy 215.9 110.49)
		)
		(stroke
			(width 0)
			(type default)
		)
	)
	(wire
		(pts
			(xy 71.12 154.94) (xy 85.09 154.94)
		)
		(stroke
			(width 0)
			(type default)
		)
	)
	(bus
		(pts
			(xy 68.58 76.2) (xy 68.58 78.74)
		)
		(stroke
			(width 0)
			(type default)
		)
	)
	(wire
		(pts
			(xy 374.65 240.03) (xy 374.65 238.76)
		)
		(stroke
			(width 0)
			(type default)
		)
	)
	(wire
		(pts
			(xy 115.57 223.52) (xy 129.54 223.52)
		)
		(stroke
			(width 0)
			(type default)
		)
	)
	(wire
		(pts
			(xy 243.84 264.16) (xy 243.84 265.43)
		)
		(stroke
			(width 0)
			(type default)
		)
	)
	(wire
		(pts
			(xy 308.61 49.53) (xy 323.85 49.53)
		)
		(stroke
			(width 0)
			(type default)
		)
	)
	(bus
		(pts
			(xy 68.58 60.96) (xy 68.58 63.5)
		)
		(stroke
			(width 0)
			(type default)
		)
	)
	(bus
		(pts
			(xy 68.58 121.92) (xy 68.58 127)
		)
		(stroke
			(width 0)
			(type default)
		)
	)
	(bus
		(pts
			(xy 306.07 64.77) (xy 306.07 67.31)
		)
		(stroke
			(width 0)
			(type default)
		)
	)
	(bus
		(pts
			(xy 139.7 50.8) (xy 133.35 50.8)
		)
		(stroke
			(width 0)
			(type default)
		)
	)
	(wire
		(pts
			(xy 115.57 200.66) (xy 129.54 200.66)
		)
		(stroke
			(width 0)
			(type default)
		)
	)
	(wire
		(pts
			(xy 308.61 67.31) (xy 323.85 67.31)
		)
		(stroke
			(width 0)
			(type default)
		)
	)
	(wire
		(pts
			(xy 308.61 59.69) (xy 323.85 59.69)
		)
		(stroke
			(width 0)
			(type default)
		)
	)
	(bus
		(pts
			(xy 68.58 144.78) (xy 68.58 147.32)
		)
		(stroke
			(width 0)
			(type default)
		)
	)
	(bus
		(pts
			(xy 306.07 62.23) (xy 306.07 64.77)
		)
		(stroke
			(width 0)
			(type default)
		)
	)
	(wire
		(pts
			(xy 115.57 73.66) (xy 129.54 73.66)
		)
		(stroke
			(width 0)
			(type default)
		)
	)
	(wire
		(pts
			(xy 71.12 78.74) (xy 85.09 78.74)
		)
		(stroke
			(width 0)
			(type default)
		)
	)
	(bus
		(pts
			(xy 132.08 81.28) (xy 132.08 83.82)
		)
		(stroke
			(width 0)
			(type default)
		)
	)
	(wire
		(pts
			(xy 288.29 167.64) (xy 288.29 166.37)
		)
		(stroke
			(width 0)
			(type default)
		)
	)
	(bus
		(pts
			(xy 374.65 67.31) (xy 374.65 69.85)
		)
		(stroke
			(width 0)
			(type default)
		)
	)
	(wire
		(pts
			(xy 245.11 154.94) (xy 270.51 154.94)
		)
		(stroke
			(width 0)
			(type default)
		)
	)
	(bus
		(pts
			(xy 132.08 86.36) (xy 132.08 88.9)
		)
		(stroke
			(width 0)
			(type default)
		)
	)
	(bus
		(pts
			(xy 68.58 63.5) (xy 68.58 66.04)
		)
		(stroke
			(width 0)
			(type default)
		)
	)
	(bus
		(pts
			(xy 132.08 76.2) (xy 132.08 78.74)
		)
		(stroke
			(width 0)
			(type default)
		)
	)
	(wire
		(pts
			(xy 215.9 92.71) (xy 226.06 92.71)
		)
		(stroke
			(width 0)
			(type default)
		)
	)
	(wire
		(pts
			(xy 115.57 210.82) (xy 129.54 210.82)
		)
		(stroke
			(width 0)
			(type default)
		)
	)
	(wire
		(pts
			(xy 308.61 80.01) (xy 323.85 80.01)
		)
		(stroke
			(width 0)
			(type default)
		)
	)
	(wire
		(pts
			(xy 251.46 161.29) (xy 251.46 158.75)
		)
		(stroke
			(width 0)
			(type default)
		)
	)
	(wire
		(pts
			(xy 215.9 40.64) (xy 215.9 41.91)
		)
		(stroke
			(width 0)
			(type default)
		)
	)
	(bus
		(pts
			(xy 132.08 218.44) (xy 132.08 220.98)
		)
		(stroke
			(width 0)
			(type default)
		)
	)
	(bus
		(pts
			(xy 132.08 104.14) (xy 132.08 106.68)
		)
		(stroke
			(width 0)
			(type default)
		)
	)
	(wire
		(pts
			(xy 354.33 240.03) (xy 354.33 238.76)
		)
		(stroke
			(width 0)
			(type default)
		)
	)
	(wire
		(pts
			(xy 308.61 77.47) (xy 323.85 77.47)
		)
		(stroke
			(width 0)
			(type default)
		)
	)
	(wire
		(pts
			(xy 314.96 90.17) (xy 323.85 90.17)
		)
		(stroke
			(width 0)
			(type default)
		)
	)
	(bus
		(pts
			(xy 68.58 139.7) (xy 68.58 142.24)
		)
		(stroke
			(width 0)
			(type default)
		)
	)
	(wire
		(pts
			(xy 281.94 109.22) (xy 281.94 110.49)
		)
		(stroke
			(width 0)
			(type default)
		)
	)
	(wire
		(pts
			(xy 71.12 203.2) (xy 85.09 203.2)
		)
		(stroke
			(width 0)
			(type default)
		)
	)
	(bus
		(pts
			(xy 68.58 127) (xy 68.58 129.54)
		)
		(stroke
			(width 0)
			(type default)
		)
	)
	(bus
		(pts
			(xy 68.58 172.72) (xy 68.58 175.26)
		)
		(stroke
			(width 0)
			(type default)
		)
	)
	(bus
		(pts
			(xy 375.92 52.07) (xy 374.65 53.34)
		)
		(stroke
			(width 0)
			(type default)
		)
	)
	(wire
		(pts
			(xy 115.57 114.3) (xy 129.54 114.3)
		)
		(stroke
			(width 0)
			(type default)
		)
	)
	(bus
		(pts
			(xy 132.08 147.32) (xy 132.08 149.86)
		)
		(stroke
			(width 0)
			(type default)
		)
	)
	(bus
		(pts
			(xy 374.65 62.23) (xy 374.65 64.77)
		)
		(stroke
			(width 0)
			(type default)
		)
	)
	(polyline
		(pts
			(xy 317.5 213.36) (xy 407.67 213.36)
		)
		(stroke
			(width 0)
			(type default)
		)
	)
	(wire
		(pts
			(xy 215.9 104.14) (xy 215.9 102.87)
		)
		(stroke
			(width 0)
			(type default)
		)
	)
	(wire
		(pts
			(xy 226.06 62.23) (xy 226.06 60.96)
		)
		(stroke
			(width 0)
			(type default)
		)
	)
	(bus
		(pts
			(xy 306.07 38.1) (xy 306.07 39.37)
		)
		(stroke
			(width 0)
			(type default)
		)
	)
	(bus
		(pts
			(xy 68.58 147.32) (xy 68.58 149.86)
		)
		(stroke
			(width 0)
			(type default)
		)
	)
	(bus
		(pts
			(xy 306.07 69.85) (xy 306.07 72.39)
		)
		(stroke
			(width 0)
			(type default)
		)
	)
	(bus
		(pts
			(xy 68.58 116.84) (xy 68.58 119.38)
		)
		(stroke
			(width 0)
			(type default)
		)
	)
	(wire
		(pts
			(xy 354.33 46.99) (xy 372.11 46.99)
		)
		(stroke
			(width 0)
			(type default)
		)
	)
	(wire
		(pts
			(xy 115.57 172.72) (xy 129.54 172.72)
		)
		(stroke
			(width 0)
			(type default)
		)
	)
	(wire
		(pts
			(xy 71.12 139.7) (xy 85.09 139.7)
		)
		(stroke
			(width 0)
			(type default)
		)
	)
	(wire
		(pts
			(xy 215.9 54.61) (xy 215.9 52.07)
		)
		(stroke
			(width 0)
			(type default)
		)
	)
	(wire
		(pts
			(xy 345.44 168.91) (xy 345.44 170.18)
		)
		(stroke
			(width 0)
			(type default)
		)
	)
	(polyline
		(pts
			(xy 227.33 234.95) (xy 227.33 241.3)
		)
		(stroke
			(width 0)
			(type default)
		)
	)
	(wire
		(pts
			(xy 115.57 190.5) (xy 129.54 190.5)
		)
		(stroke
			(width 0)
			(type default)
		)
	)
	(bus
		(pts
			(xy 132.08 185.42) (xy 132.08 187.96)
		)
		(stroke
			(width 0)
			(type default)
		)
	)
	(wire
		(pts
			(xy 115.57 208.28) (xy 129.54 208.28)
		)
		(stroke
			(width 0)
			(type default)
		)
	)
	(wire
		(pts
			(xy 115.57 109.22) (xy 129.54 109.22)
		)
		(stroke
			(width 0)
			(type default)
		)
	)
	(wire
		(pts
			(xy 115.57 149.86) (xy 129.54 149.86)
		)
		(stroke
			(width 0)
			(type default)
		)
	)
	(wire
		(pts
			(xy 354.33 95.25) (xy 356.87 95.25)
		)
		(stroke
			(width 0)
			(type default)
		)
	)
	(wire
		(pts
			(xy 354.33 36.83) (xy 372.11 36.83)
		)
		(stroke
			(width 0)
			(type default)
		)
	)
	(bus
		(pts
			(xy 132.08 195.58) (xy 132.08 198.12)
		)
		(stroke
			(width 0)
			(type default)
		)
	)
	(wire
		(pts
			(xy 71.12 137.16) (xy 85.09 137.16)
		)
		(stroke
			(width 0)
			(type default)
		)
	)
	(wire
		(pts
			(xy 248.92 39.37) (xy 248.92 40.64)
		)
		(stroke
			(width 0)
			(type default)
		)
	)
	(wire
		(pts
			(xy 251.46 204.47) (xy 251.46 200.66)
		)
		(stroke
			(width 0)
			(type default)
		)
	)
	(wire
		(pts
			(xy 226.06 41.91) (xy 226.06 43.18)
		)
		(stroke
			(width 0)
			(type default)
		)
	)
	(wire
		(pts
			(xy 71.12 121.92) (xy 85.09 121.92)
		)
		(stroke
			(width 0)
			(type default)
		)
	)
	(wire
		(pts
			(xy 115.57 175.26) (xy 129.54 175.26)
		)
		(stroke
			(width 0)
			(type default)
		)
	)
	(bus
		(pts
			(xy 132.08 119.38) (xy 132.08 121.92)
		)
		(stroke
			(width 0)
			(type default)
		)
	)
	(bus
		(pts
			(xy 132.08 177.8) (xy 132.08 180.34)
		)
		(stroke
			(width 0)
			(type default)
		)
	)
	(bus
		(pts
			(xy 68.58 66.04) (xy 68.58 68.58)
		)
		(stroke
			(width 0)
			(type default)
		)
	)
	(wire
		(pts
			(xy 71.12 142.24) (xy 85.09 142.24)
		)
		(stroke
			(width 0)
			(type default)
		)
	)
	(bus
		(pts
			(xy 132.08 200.66) (xy 132.08 203.2)
		)
		(stroke
			(width 0)
			(type default)
		)
	)
	(bus
		(pts
			(xy 68.58 187.96) (xy 68.58 193.04)
		)
		(stroke
			(width 0)
			(type default)
		)
	)
	(wire
		(pts
			(xy 115.57 88.9) (xy 129.54 88.9)
		)
		(stroke
			(width 0)
			(type default)
		)
	)
	(wire
		(pts
			(xy 313.69 36.83) (xy 323.85 36.83)
		)
		(stroke
			(width 0)
			(type default)
		)
	)
	(bus
		(pts
			(xy 132.08 111.76) (xy 132.08 114.3)
		)
		(stroke
			(width 0)
			(type default)
		)
	)
	(polyline
		(pts
			(xy 241.3 254) (xy 299.72 254)
		)
		(stroke
			(width 0)
			(type default)
		)
	)
	(bus
		(pts
			(xy 132.08 116.84) (xy 132.08 119.38)
		)
		(stroke
			(width 0)
			(type default)
		)
	)
	(bus
		(pts
			(xy 374.65 59.69) (xy 374.65 62.23)
		)
		(stroke
			(width 0)
			(type default)
		)
	)
	(bus
		(pts
			(xy 374.65 64.77) (xy 374.65 67.31)
		)
		(stroke
			(width 0)
			(type default)
		)
	)
	(bus
		(pts
			(xy 132.08 66.04) (xy 132.08 68.58)
		)
		(stroke
			(width 0)
			(type default)
		)
	)
	(bus
		(pts
			(xy 68.58 129.54) (xy 68.58 132.08)
		)
		(stroke
			(width 0)
			(type default)
		)
	)
	(wire
		(pts
			(xy 345.44 180.34) (xy 345.44 185.42)
		)
		(stroke
			(width 0)
			(type default)
		)
	)
	(wire
		(pts
			(xy 71.12 119.38) (xy 85.09 119.38)
		)
		(stroke
			(width 0)
			(type default)
		)
	)
	(wire
		(pts
			(xy 308.61 46.99) (xy 323.85 46.99)
		)
		(stroke
			(width 0)
			(type default)
		)
	)
	(wire
		(pts
			(xy 71.12 220.98) (xy 85.09 220.98)
		)
		(stroke
			(width 0)
			(type default)
		)
	)
	(wire
		(pts
			(xy 372.11 39.37) (xy 354.33 39.37)
		)
		(stroke
			(width 0)
			(type default)
		)
	)
	(wire
		(pts
			(xy 251.46 158.75) (xy 245.11 158.75)
		)
		(stroke
			(width 0)
			(type default)
		)
	)
	(wire
		(pts
			(xy 115.57 132.08) (xy 129.54 132.08)
		)
		(stroke
			(width 0)
			(type default)
		)
	)
	(polyline
		(pts
			(xy 194.31 238.76) (xy 243.84 238.76)
		)
		(stroke
			(width 0)
			(type default)
		)
	)
	(wire
		(pts
			(xy 270.51 154.94) (xy 270.51 161.29)
		)
		(stroke
			(width 0)
			(type default)
		)
	)
	(wire
		(pts
			(xy 71.12 162.56) (xy 85.09 162.56)
		)
		(stroke
			(width 0)
			(type default)
		)
	)
	(wire
		(pts
			(xy 271.78 116.84) (xy 271.78 115.57)
		)
		(stroke
			(width 0)
			(type default)
		)
	)
	(bus
		(pts
			(xy 68.58 114.3) (xy 68.58 116.84)
		)
		(stroke
			(width 0)
			(type default)
		)
	)
	(wire
		(pts
			(xy 356.87 95.25) (xy 356.87 97.79)
		)
		(stroke
			(width 0)
			(type default)
		)
	)
	(wire
		(pts
			(xy 115.57 124.46) (xy 129.54 124.46)
		)
		(stroke
			(width 0)
			(type default)
		)
	)
	(wire
		(pts
			(xy 215.9 110.49) (xy 226.06 110.49)
		)
		(stroke
			(width 0)
			(type default)
		)
	)
	(bus
		(pts
			(xy 68.58 210.82) (xy 68.58 213.36)
		)
		(stroke
			(width 0)
			(type default)
		)
	)
	(wire
		(pts
			(xy 284.48 234.95) (xy 280.67 234.95)
		)
		(stroke
			(width 0)
			(type default)
		)
	)
	(bus
		(pts
			(xy 132.08 149.86) (xy 132.08 152.4)
		)
		(stroke
			(width 0)
			(type default)
		)
	)
	(bus
		(pts
			(xy 132.08 162.56) (xy 132.08 165.1)
		)
		(stroke
			(width 0)
			(type default)
		)
	)
	(wire
		(pts
			(xy 374.65 232.41) (xy 374.65 233.68)
		)
		(stroke
			(width 0)
			(type default)
		)
	)
	(bus
		(pts
			(xy 68.58 170.18) (xy 68.58 172.72)
		)
		(stroke
			(width 0)
			(type default)
		)
	)
	(bus
		(pts
			(xy 68.58 109.22) (xy 68.58 111.76)
		)
		(stroke
			(width 0)
			(type default)
		)
	)
	(bus
		(pts
			(xy 132.08 167.64) (xy 132.08 170.18)
		)
		(stroke
			(width 0)
			(type default)
		)
	)
	(wire
		(pts
			(xy 215.9 52.07) (xy 218.44 52.07)
		)
		(stroke
			(width 0)
			(type default)
		)
	)
	(bus
		(pts
			(xy 132.08 88.9) (xy 132.08 93.98)
		)
		(stroke
			(width 0)
			(type default)
		)
	)
	(wire
		(pts
			(xy 270.51 190.5) (xy 270.51 204.47)
		)
		(stroke
			(width 0)
			(type default)
		)
	)
	(wire
		(pts
			(xy 115.57 116.84) (xy 129.54 116.84)
		)
		(stroke
			(width 0)
			(type default)
		)
	)
	(bus
		(pts
			(xy 132.08 137.16) (xy 132.08 139.7)
		)
		(stroke
			(width 0)
			(type default)
		)
	)
	(wire
		(pts
			(xy 115.57 205.74) (xy 129.54 205.74)
		)
		(stroke
			(width 0)
			(type default)
		)
	)
	(wire
		(pts
			(xy 115.57 121.92) (xy 129.54 121.92)
		)
		(stroke
			(width 0)
			(type default)
		)
	)
	(wire
		(pts
			(xy 372.11 41.91) (xy 354.33 41.91)
		)
		(stroke
			(width 0)
			(type default)
		)
	)
	(bus
		(pts
			(xy 132.08 71.12) (xy 132.08 73.66)
		)
		(stroke
			(width 0)
			(type default)
		)
	)
	(wire
		(pts
			(xy 234.95 82.55) (xy 248.92 82.55)
		)
		(stroke
			(width 0)
			(type default)
		)
	)
	(bus
		(pts
			(xy 132.08 208.28) (xy 132.08 210.82)
		)
		(stroke
			(width 0)
			(type default)
		)
	)
	(polyline
		(pts
			(xy 190.5 129.54) (xy 407.67 129.54)
		)
		(stroke
			(width 0)
			(type default)
		)
	)
	(wire
		(pts
			(xy 281.94 100.33) (xy 281.94 99.06)
		)
		(stroke
			(width 0)
			(type default)
		)
	)
	(bus
		(pts
			(xy 374.65 74.93) (xy 374.65 77.47)
		)
		(stroke
			(width 0)
			(type default)
		)
	)
	(wire
		(pts
			(xy 71.12 218.44) (xy 85.09 218.44)
		)
		(stroke
			(width 0)
			(type default)
		)
	)
	(bus
		(pts
			(xy 132.08 99.06) (xy 132.08 101.6)
		)
		(stroke
			(width 0)
			(type default)
		)
	)
	(bus
		(pts
			(xy 132.08 170.18) (xy 132.08 172.72)
		)
		(stroke
			(width 0)
			(type default)
		)
	)
	(wire
		(pts
			(xy 288.29 151.13) (xy 288.29 161.29)
		)
		(stroke
			(width 0)
			(type default)
		)
	)
	(bus
		(pts
			(xy 68.58 83.82) (xy 68.58 86.36)
		)
		(stroke
			(width 0)
			(type default)
		)
	)
	(wire
		(pts
			(xy 354.33 59.69) (xy 372.11 59.69)
		)
		(stroke
			(width 0)
			(type default)
		)
	)
	(wire
		(pts
			(xy 281.94 116.84) (xy 281.94 115.57)
		)
		(stroke
			(width 0)
			(type default)
		)
	)
	(wire
		(pts
			(xy 308.61 72.39) (xy 323.85 72.39)
		)
		(stroke
			(width 0)
			(type default)
		)
	)
	(wire
		(pts
			(xy 115.57 129.54) (xy 129.54 129.54)
		)
		(stroke
			(width 0)
			(type default)
		)
	)
	(wire
		(pts
			(xy 248.92 81.28) (xy 248.92 82.55)
		)
		(stroke
			(width 0)
			(type default)
		)
	)
	(wire
		(pts
			(xy 215.9 82.55) (xy 215.9 85.09)
		)
		(stroke
			(width 0)
			(type default)
		)
	)
	(bus
		(pts
			(xy 375.92 34.29) (xy 383.54 34.29)
		)
		(stroke
			(width 0)
			(type default)
		)
	)
	(wire
		(pts
			(xy 308.61 64.77) (xy 323.85 64.77)
		)
		(stroke
			(width 0)
			(type default)
		)
	)
	(bus
		(pts
			(xy 67.31 50.8) (xy 68.58 52.07)
		)
		(stroke
			(width 0)
			(type default)
		)
	)
	(wire
		(pts
			(xy 248.92 33.02) (xy 248.92 34.29)
		)
		(stroke
			(width 0)
			(type default)
		)
	)
	(wire
		(pts
			(xy 71.12 147.32) (xy 85.09 147.32)
		)
		(stroke
			(width 0)
			(type default)
		)
	)
	(wire
		(pts
			(xy 226.06 92.71) (xy 226.06 93.98)
		)
		(stroke
			(width 0)
			(type default)
		)
	)
	(bus
		(pts
			(xy 306.07 67.31) (xy 306.07 69.85)
		)
		(stroke
			(width 0)
			(type default)
		)
	)
	(wire
		(pts
			(xy 71.12 63.5) (xy 85.09 63.5)
		)
		(stroke
			(width 0)
			(type default)
		)
	)
	(wire
		(pts
			(xy 71.12 157.48) (xy 85.09 157.48)
		)
		(stroke
			(width 0)
			(type default)
		)
	)
	(bus
		(pts
			(xy 68.58 200.66) (xy 68.58 203.2)
		)
		(stroke
			(width 0)
			(type default)
		)
	)
	(bus
		(pts
			(xy 132.08 160.02) (xy 132.08 162.56)
		)
		(stroke
			(width 0)
			(type default)
		)
	)
	(wire
		(pts
			(xy 115.57 66.04) (xy 129.54 66.04)
		)
		(stroke
			(width 0)
			(type default)
		)
	)
	(wire
		(pts
			(xy 226.06 110.49) (xy 226.06 106.68)
		)
		(stroke
			(width 0)
			(type default)
		)
	)
	(bus
		(pts
			(xy 68.58 81.28) (xy 68.58 83.82)
		)
		(stroke
			(width 0)
			(type default)
		)
	)
	(bus
		(pts
			(xy 68.58 205.74) (xy 68.58 208.28)
		)
		(stroke
			(width 0)
			(type default)
		)
	)
	(bus
		(pts
			(xy 132.08 205.74) (xy 132.08 208.28)
		)
		(stroke
			(width 0)
			(type default)
		)
	)
	(wire
		(pts
			(xy 354.33 232.41) (xy 354.33 233.68)
		)
		(stroke
			(width 0)
			(type default)
		)
	)
	(wire
		(pts
			(xy 71.12 68.58) (xy 85.09 68.58)
		)
		(stroke
			(width 0)
			(type default)
		)
	)
	(bus
		(pts
			(xy 68.58 149.86) (xy 68.58 152.4)
		)
		(stroke
			(width 0)
			(type default)
		)
	)
	(polyline
		(pts
			(xy 317.5 252.73) (xy 317.5 213.36)
		)
		(stroke
			(width 0)
			(type default)
		)
	)
	(bus
		(pts
			(xy 132.08 165.1) (xy 132.08 167.64)
		)
		(stroke
			(width 0)
			(type default)
		)
	)
	(bus
		(pts
			(xy 374.65 35.56) (xy 374.65 36.83)
		)
		(stroke
			(width 0)
			(type default)
		)
	)
	(bus
		(pts
			(xy 374.65 44.45) (xy 374.65 46.99)
		)
		(stroke
			(width 0)
			(type default)
		)
	)
	(bus
		(pts
			(xy 375.92 52.07) (xy 382.27 52.07)
		)
		(stroke
			(width 0)
			(type default)
		)
	)
	(wire
		(pts
			(xy 248.92 45.72) (xy 248.92 48.26)
		)
		(stroke
			(width 0)
			(type default)
		)
	)
	(bus
		(pts
			(xy 132.08 187.96) (xy 132.08 193.04)
		)
		(stroke
			(width 0)
			(type default)
		)
	)
	(bus
		(pts
			(xy 68.58 88.9) (xy 68.58 93.98)
		)
		(stroke
			(width 0)
			(type default)
		)
	)
	(wire
		(pts
			(xy 71.12 165.1) (xy 85.09 165.1)
		)
		(stroke
			(width 0)
			(type default)
		)
	)
	(bus
		(pts
			(xy 132.08 152.4) (xy 132.08 154.94)
		)
		(stroke
			(width 0)
			(type default)
		)
	)
	(wire
		(pts
			(xy 71.12 205.74) (xy 85.09 205.74)
		)
		(stroke
			(width 0)
			(type default)
		)
	)
	(wire
		(pts
			(xy 347.98 168.91) (xy 347.98 170.18)
		)
		(stroke
			(width 0)
			(type default)
		)
	)
	(bus
		(pts
			(xy 132.08 182.88) (xy 132.08 185.42)
		)
		(stroke
			(width 0)
			(type default)
		)
	)
	(bus
		(pts
			(xy 132.08 154.94) (xy 132.08 160.02)
		)
		(stroke
			(width 0)
			(type default)
		)
	)
	(wire
		(pts
			(xy 71.12 73.66) (xy 85.09 73.66)
		)
		(stroke
			(width 0)
			(type default)
		)
	)
	(wire
		(pts
			(xy 354.33 77.47) (xy 372.11 77.47)
		)
		(stroke
			(width 0)
			(type default)
		)
	)
	(wire
		(pts
			(xy 215.9 41.91) (xy 226.06 41.91)
		)
		(stroke
			(width 0)
			(type default)
		)
	)
	(wire
		(pts
			(xy 271.78 109.22) (xy 271.78 110.49)
		)
		(stroke
			(width 0)
			(type default)
		)
	)
	(bus
		(pts
			(xy 306.07 39.37) (xy 306.07 44.45)
		)
		(stroke
			(width 0)
			(type default)
		)
	)
	(wire
		(pts
			(xy 71.12 167.64) (xy 85.09 167.64)
		)
		(stroke
			(width 0)
			(type default)
		)
	)
	(bus
		(pts
			(xy 132.08 114.3) (xy 132.08 116.84)
		)
		(stroke
			(width 0)
			(type default)
		)
	)
	(bus
		(pts
			(xy 375.92 41.91) (xy 383.54 41.91)
		)
		(stroke
			(width 0)
			(type default)
		)
	)
	(wire
		(pts
			(xy 71.12 198.12) (xy 85.09 198.12)
		)
		(stroke
			(width 0)
			(type default)
		)
	)
	(wire
		(pts
			(xy 115.57 182.88) (xy 129.54 182.88)
		)
		(stroke
			(width 0)
			(type default)
		)
	)
	(wire
		(pts
			(xy 345.44 185.42) (xy 347.98 185.42)
		)
		(stroke
			(width 0)
			(type default)
		)
	)
	(bus
		(pts
			(xy 132.08 83.82) (xy 132.08 86.36)
		)
		(stroke
			(width 0)
			(type default)
		)
	)
	(wire
		(pts
			(xy 214.63 82.55) (xy 215.9 82.55)
		)
		(stroke
			(width 0)
			(type default)
		)
	)
	(wire
		(pts
			(xy 115.57 139.7) (xy 129.54 139.7)
		)
		(stroke
			(width 0)
			(type default)
		)
	)
	(wire
		(pts
			(xy 356.87 180.34) (xy 356.87 185.42)
		)
		(stroke
			(width 0)
			(type default)
		)
	)
	(wire
		(pts
			(xy 248.92 31.75) (xy 248.92 33.02)
		)
		(stroke
			(width 0)
			(type default)
		)
	)
	(wire
		(pts
			(xy 271.78 100.33) (xy 271.78 99.06)
		)
		(stroke
			(width 0)
			(type default)
		)
	)
	(wire
		(pts
			(xy 234.95 33.02) (xy 248.92 33.02)
		)
		(stroke
			(width 0)
			(type default)
		)
	)
	(wire
		(pts
			(xy 115.57 165.1) (xy 129.54 165.1)
		)
		(stroke
			(width 0)
			(type default)
		)
	)
	(bus
		(pts
			(xy 306.07 44.45) (xy 306.07 46.99)
		)
		(stroke
			(width 0)
			(type default)
		)
	)
	(wire
		(pts
			(xy 71.12 81.28) (xy 85.09 81.28)
		)
		(stroke
			(width 0)
			(type default)
		)
	)
	(bus
		(pts
			(xy 68.58 167.64) (xy 68.58 170.18)
		)
		(stroke
			(width 0)
			(type default)
		)
	)
	(polyline
		(pts
			(xy 190.5 25.4) (xy 190.5 284.48)
		)
		(stroke
			(width 0)
			(type default)
		)
	)
	(bus
		(pts
			(xy 306.07 72.39) (xy 306.07 74.93)
		)
		(stroke
			(width 0)
			(type default)
		)
	)
	(wire
		(pts
			(xy 214.63 31.75) (xy 214.63 33.02)
		)
		(stroke
			(width 0)
			(type default)
		)
	)
	(wire
		(pts
			(xy 308.61 52.07) (xy 323.85 52.07)
		)
		(stroke
			(width 0)
			(type default)
		)
	)
	(wire
		(pts
			(xy 354.33 67.31) (xy 372.11 67.31)
		)
		(stroke
			(width 0)
			(type default)
		)
	)
	(wire
		(pts
			(xy 347.98 158.75) (xy 347.98 161.29)
		)
		(stroke
			(width 0)
			(type default)
		)
	)
	(polyline
		(pts
			(xy 194.31 241.3) (xy 243.84 241.3)
		)
		(stroke
			(width 0)
			(type default)
		)
	)
	(wire
		(pts
			(xy 71.12 210.82) (xy 85.09 210.82)
		)
		(stroke
			(width 0)
			(type default)
		)
	)
	(wire
		(pts
			(xy 308.61 69.85) (xy 323.85 69.85)
		)
		(stroke
			(width 0)
			(type default)
		)
	)
	(bus
		(pts
			(xy 306.07 46.99) (xy 306.07 49.53)
		)
		(stroke
			(width 0)
			(type default)
		)
	)
	(wire
		(pts
			(xy 115.57 142.24) (xy 129.54 142.24)
		)
		(stroke
			(width 0)
			(type default)
		)
	)
	(wire
		(pts
			(xy 271.78 231.14) (xy 271.78 234.95)
		)
		(stroke
			(width 0)
			(type default)
		)
	)
	(bus
		(pts
			(xy 68.58 93.98) (xy 68.58 96.52)
		)
		(stroke
			(width 0)
			(type default)
		)
	)
	(bus
		(pts
			(xy 132.08 109.22) (xy 132.08 111.76)
		)
		(stroke
			(width 0)
			(type default)
		)
	)
	(wire
		(pts
			(xy 248.92 96.52) (xy 248.92 97.79)
		)
		(stroke
			(width 0)
			(type default)
		)
	)
	(bus
		(pts
			(xy 306.07 74.93) (xy 306.07 77.47)
		)
		(stroke
			(width 0)
			(type default)
		)
	)
	(wire
		(pts
			(xy 115.57 96.52) (xy 129.54 96.52)
		)
		(stroke
			(width 0)
			(type default)
		)
	)
	(wire
		(pts
			(xy 245.11 151.13) (xy 288.29 151.13)
		)
		(stroke
			(width 0)
			(type default)
		)
	)
	(wire
		(pts
			(xy 71.12 223.52) (xy 85.09 223.52)
		)
		(stroke
			(width 0)
			(type default)
		)
	)
	(wire
		(pts
			(xy 115.57 154.94) (xy 129.54 154.94)
		)
		(stroke
			(width 0)
			(type default)
		)
	)
	(bus
		(pts
			(xy 68.58 208.28) (xy 68.58 210.82)
		)
		(stroke
			(width 0)
			(type default)
		)
	)
	(wire
		(pts
			(xy 115.57 134.62) (xy 129.54 134.62)
		)
		(stroke
			(width 0)
			(type default)
		)
	)
	(wire
		(pts
			(xy 364.49 232.41) (xy 364.49 233.68)
		)
		(stroke
			(width 0)
			(type default)
		)
	)
	(wire
		(pts
			(xy 347.98 180.34) (xy 347.98 185.42)
		)
		(stroke
			(width 0)
			(type default)
		)
	)
	(bus
		(pts
			(xy 60.96 50.8) (xy 67.31 50.8)
		)
		(stroke
			(width 0)
			(type default)
		)
	)
	(wire
		(pts
			(xy 71.12 208.28) (xy 85.09 208.28)
		)
		(stroke
			(width 0)
			(type default)
		)
	)
	(wire
		(pts
			(xy 71.12 172.72) (xy 85.09 172.72)
		)
		(stroke
			(width 0)
			(type default)
		)
	)
	(bus
		(pts
			(xy 374.65 57.15) (xy 374.65 59.69)
		)
		(stroke
			(width 0)
			(type default)
		)
	)
	(wire
		(pts
			(xy 242.57 186.69) (xy 262.89 186.69)
		)
		(stroke
			(width 0)
			(type default)
		)
	)
	(wire
		(pts
			(xy 214.63 102.87) (xy 215.9 102.87)
		)
		(stroke
			(width 0)
			(type default)
		)
	)
	(bus
		(pts
			(xy 132.08 142.24) (xy 132.08 144.78)
		)
		(stroke
			(width 0)
			(type default)
		)
	)
	(wire
		(pts
			(xy 115.57 220.98) (xy 129.54 220.98)
		)
		(stroke
			(width 0)
			(type default)
		)
	)
	(wire
		(pts
			(xy 71.12 66.04) (xy 85.09 66.04)
		)
		(stroke
			(width 0)
			(type default)
		)
	)
	(bus
		(pts
			(xy 132.08 144.78) (xy 132.08 147.32)
		)
		(stroke
			(width 0)
			(type default)
		)
	)
	(wire
		(pts
			(xy 115.57 213.36) (xy 129.54 213.36)
		)
		(stroke
			(width 0)
			(type default)
		)
	)
	(wire
		(pts
			(xy 115.57 215.9) (xy 129.54 215.9)
		)
		(stroke
			(width 0)
			(type default)
		)
	)
	(wire
		(pts
			(xy 71.12 144.78) (xy 85.09 144.78)
		)
		(stroke
			(width 0)
			(type default)
		)
	)
	(wire
		(pts
			(xy 71.12 195.58) (xy 85.09 195.58)
		)
		(stroke
			(width 0)
			(type default)
		)
	)
	(wire
		(pts
			(xy 322.58 100.33) (xy 322.58 92.71)
		)
		(stroke
			(width 0)
			(type default)
		)
	)
	(wire
		(pts
			(xy 71.12 149.86) (xy 85.09 149.86)
		)
		(stroke
			(width 0)
			(type default)
		)
	)
	(bus
		(pts
			(xy 68.58 165.1) (xy 68.58 167.64)
		)
		(stroke
			(width 0)
			(type default)
		)
	)
	(bus
		(pts
			(xy 68.58 198.12) (xy 68.58 200.66)
		)
		(stroke
			(width 0)
			(type default)
		)
	)
	(wire
		(pts
			(xy 354.33 72.39) (xy 372.11 72.39)
		)
		(stroke
			(width 0)
			(type default)
		)
	)
	(wire
		(pts
			(xy 71.12 187.96) (xy 85.09 187.96)
		)
		(stroke
			(width 0)
			(type default)
		)
	)
	(wire
		(pts
			(xy 115.57 99.06) (xy 129.54 99.06)
		)
		(stroke
			(width 0)
			(type default)
		)
	)
	(bus
		(pts
			(xy 132.08 215.9) (xy 132.08 218.44)
		)
		(stroke
			(width 0)
			(type default)
		)
	)
	(bus
		(pts
			(xy 132.08 134.62) (xy 132.08 137.16)
		)
		(stroke
			(width 0)
			(type default)
		)
	)
	(bus
		(pts
			(xy 132.08 52.07) (xy 132.08 60.96)
		)
		(stroke
			(width 0)
			(type default)
		)
	)
	(wire
		(pts
			(xy 71.12 88.9) (xy 85.09 88.9)
		)
		(stroke
			(width 0)
			(type default)
		)
	)
	(bus
		(pts
			(xy 306.07 54.61) (xy 306.07 57.15)
		)
		(stroke
			(width 0)
			(type default)
		)
	)
	(bus
		(pts
			(xy 374.65 53.34) (xy 374.65 54.61)
		)
		(stroke
			(width 0)
			(type default)
		)
	)
	(bus
		(pts
			(xy 132.08 198.12) (xy 132.08 200.66)
		)
		(stroke
			(width 0)
			(type default)
		)
	)
	(wire
		(pts
			(xy 270.51 166.37) (xy 270.51 177.8)
		)
		(stroke
			(width 0)
			(type default)
		)
	)
	(bus
		(pts
			(xy 68.58 203.2) (xy 68.58 205.74)
		)
		(stroke
			(width 0)
			(type default)
		)
	)
	(wire
		(pts
			(xy 71.12 175.26) (xy 85.09 175.26)
		)
		(stroke
			(width 0)
			(type default)
		)
	)
	(bus
		(pts
			(xy 132.08 73.66) (xy 132.08 76.2)
		)
		(stroke
			(width 0)
			(type default)
		)
	)
	(wire
		(pts
			(xy 71.12 96.52) (xy 85.09 96.52)
		)
		(stroke
			(width 0)
			(type default)
		)
	)
	(bus
		(pts
			(xy 68.58 99.06) (xy 68.58 101.6)
		)
		(stroke
			(width 0)
			(type default)
		)
	)
	(bus
		(pts
			(xy 132.08 68.58) (xy 132.08 71.12)
		)
		(stroke
			(width 0)
			(type default)
		)
	)
	(wire
		(pts
			(xy 308.61 57.15) (xy 323.85 57.15)
		)
		(stroke
			(width 0)
			(type default)
		)
	)
	(polyline
		(pts
			(xy 317.5 129.54) (xy 317.5 213.36)
		)
		(stroke
			(width 0)
			(type default)
		)
	)
	(bus
		(pts
			(xy 68.58 78.74) (xy 68.58 81.28)
		)
		(stroke
			(width 0)
			(type default)
		)
	)
	(bus
		(pts
			(xy 132.08 106.68) (xy 132.08 109.22)
		)
		(stroke
			(width 0)
			(type default)
		)
	)
	(bus
		(pts
			(xy 374.65 46.99) (xy 374.65 49.53)
		)
		(stroke
			(width 0)
			(type default)
		)
	)
	(wire
		(pts
			(xy 354.33 64.77) (xy 372.11 64.77)
		)
		(stroke
			(width 0)
			(type default)
		)
	)
	(bus
		(pts
			(xy 306.07 38.1) (xy 304.8 36.83)
		)
		(stroke
			(width 0)
			(type default)
		)
	)
	(wire
		(pts
			(xy 356.87 100.33) (xy 356.87 97.79)
		)
		(stroke
			(width 0)
			(type default)
		)
	)
	(wire
		(pts
			(xy 354.33 74.93) (xy 372.11 74.93)
		)
		(stroke
			(width 0)
			(type default)
		)
	)
	(bus
		(pts
			(xy 298.45 52.07) (xy 304.8 52.07)
		)
		(stroke
			(width 0)
			(type default)
		)
	)
	(bus
		(pts
			(xy 68.58 104.14) (xy 68.58 106.68)
		)
		(stroke
			(width 0)
			(type default)
		)
	)
	(wire
		(pts
			(xy 308.61 74.93) (xy 323.85 74.93)
		)
		(stroke
			(width 0)
			(type default)
		)
	)
	(wire
		(pts
			(xy 115.57 81.28) (xy 129.54 81.28)
		)
		(stroke
			(width 0)
			(type default)
		)
	)
	(wire
		(pts
			(xy 354.33 49.53) (xy 372.11 49.53)
		)
		(stroke
			(width 0)
			(type default)
		)
	)
	(wire
		(pts
			(xy 215.9 59.69) (xy 215.9 60.96)
		)
		(stroke
			(width 0)
			(type default)
		)
	)
	(bus
		(pts
			(xy 132.08 193.04) (xy 132.08 195.58)
		)
		(stroke
			(width 0)
			(type default)
		)
	)
	(bus
		(pts
			(xy 68.58 134.62) (xy 68.58 137.16)
		)
		(stroke
			(width 0)
			(type default)
		)
	)
	(bus
		(pts
			(xy 306.07 57.15) (xy 306.07 59.69)
		)
		(stroke
			(width 0)
			(type default)
		)
	)
	(wire
		(pts
			(xy 240.03 264.16) (xy 243.84 264.16)
		)
		(stroke
			(width 0)
			(type default)
		)
	)
	(wire
		(pts
			(xy 354.33 92.71) (xy 356.87 92.71)
		)
		(stroke
			(width 0)
			(type default)
		)
	)
	(bus
		(pts
			(xy 68.58 213.36) (xy 68.58 215.9)
		)
		(stroke
			(width 0)
			(type default)
		)
	)
	(bus
		(pts
			(xy 132.08 52.07) (xy 133.35 50.8)
		)
		(stroke
			(width 0)
			(type default)
		)
	)
	(wire
		(pts
			(xy 115.57 152.4) (xy 129.54 152.4)
		)
		(stroke
			(width 0)
			(type default)
		)
	)
	(wire
		(pts
			(xy 242.57 196.85) (xy 243.84 196.85)
		)
		(stroke
			(width 0)
			(type default)
		)
	)
	(wire
		(pts
			(xy 115.57 144.78) (xy 129.54 144.78)
		)
		(stroke
			(width 0)
			(type default)
		)
	)
	(wire
		(pts
			(xy 71.12 114.3) (xy 85.09 114.3)
		)
		(stroke
			(width 0)
			(type default)
		)
	)
	(bus
		(pts
			(xy 68.58 195.58) (xy 68.58 198.12)
		)
		(stroke
			(width 0)
			(type default)
		)
	)
	(wire
		(pts
			(xy 215.9 102.87) (xy 218.44 102.87)
		)
		(stroke
			(width 0)
			(type default)
		)
	)
	(wire
		(pts
			(xy 354.33 62.23) (xy 372.11 62.23)
		)
		(stroke
			(width 0)
			(type default)
		)
	)
	(bus
		(pts
			(xy 132.08 180.34) (xy 132.08 182.88)
		)
		(stroke
			(width 0)
			(type default)
		)
	)
	(wire
		(pts
			(xy 115.57 137.16) (xy 129.54 137.16)
		)
		(stroke
			(width 0)
			(type default)
		)
	)
	(wire
		(pts
			(xy 313.69 39.37) (xy 323.85 39.37)
		)
		(stroke
			(width 0)
			(type default)
		)
	)
	(bus
		(pts
			(xy 374.65 36.83) (xy 374.65 39.37)
		)
		(stroke
			(width 0)
			(type default)
		)
	)
	(wire
		(pts
			(xy 220.98 153.67) (xy 220.98 154.94)
		)
		(stroke
			(width 0)
			(type default)
		)
	)
	(wire
		(pts
			(xy 354.33 57.15) (xy 372.11 57.15)
		)
		(stroke
			(width 0)
			(type default)
		)
	)
	(bus
		(pts
			(xy 68.58 182.88) (xy 68.58 185.42)
		)
		(stroke
			(width 0)
			(type default)
		)
	)
	(wire
		(pts
			(xy 115.57 195.58) (xy 129.54 195.58)
		)
		(stroke
			(width 0)
			(type default)
		)
	)
	(wire
		(pts
			(xy 115.57 68.58) (xy 129.54 68.58)
		)
		(stroke
			(width 0)
			(type default)
		)
	)
	(bus
		(pts
			(xy 375.92 41.91) (xy 374.65 43.18)
		)
		(stroke
			(width 0)
			(type default)
		)
	)
	(wire
		(pts
			(xy 347.98 166.37) (xy 347.98 168.91)
		)
		(stroke
			(width 0)
			(type default)
		)
	)
	(wire
		(pts
			(xy 215.9 90.17) (xy 215.9 92.71)
		)
		(stroke
			(width 0)
			(type default)
		)
	)
	(wire
		(pts
			(xy 226.06 92.71) (xy 226.06 90.17)
		)
		(stroke
			(width 0)
			(type default)
		)
	)
	(wire
		(pts
			(xy 215.9 33.02) (xy 215.9 35.56)
		)
		(stroke
			(width 0)
			(type default)
		)
	)
	(wire
		(pts
			(xy 115.57 86.36) (xy 129.54 86.36)
		)
		(stroke
			(width 0)
			(type default)
		)
	)
	(wire
		(pts
			(xy 115.57 71.12) (xy 129.54 71.12)
		)
		(stroke
			(width 0)
			(type default)
		)
	)
	(bus
		(pts
			(xy 68.58 154.94) (xy 68.58 160.02)
		)
		(stroke
			(width 0)
			(type default)
		)
	)
	(bus
		(pts
			(xy 132.08 93.98) (xy 132.08 96.52)
		)
		(stroke
			(width 0)
			(type default)
		)
	)
	(bus
		(pts
			(xy 132.08 172.72) (xy 132.08 175.26)
		)
		(stroke
			(width 0)
			(type default)
		)
	)
	(bus
		(pts
			(xy 375.92 34.29) (xy 374.65 35.56)
		)
		(stroke
			(width 0)
			(type default)
		)
	)
	(label "A.DQS0_N"
		(at 71.12 76.2 0)
		(effects
			(font
				(size 1.27 1.27)
			)
			(justify left bottom)
		)
	)
	(label "A.CB1"
		(at 71.12 198.12 0)
		(effects
			(font
				(size 1.27 1.27)
			)
			(justify left bottom)
		)
	)
	(label "A.DQ12"
		(at 71.12 111.76 0)
		(effects
			(font
				(size 1.27 1.27)
			)
			(justify left bottom)
		)
	)
	(label "A.DQ2"
		(at 71.12 68.58 0)
		(effects
			(font
				(size 1.27 1.27)
			)
			(justify left bottom)
		)
	)
	(label "B.DQ20"
		(at 129.54 144.78 180)
		(effects
			(font
				(size 1.27 1.27)
			)
			(justify right bottom)
		)
	)
	(label "B.CB6"
		(at 129.54 215.9 180)
		(effects
			(font
				(size 1.27 1.27)
			)
			(justify right bottom)
		)
	)
	(label "B.DQ11"
		(at 129.54 104.14 180)
		(effects
			(font
				(size 1.27 1.27)
			)
			(justify right bottom)
		)
	)
	(label "A.DQ14"
		(at 71.12 116.84 0)
		(effects
			(font
				(size 1.27 1.27)
			)
			(justify left bottom)
		)
	)
	(label "A.DQ24"
		(at 71.12 162.56 0)
		(effects
			(font
				(size 1.27 1.27)
			)
			(justify left bottom)
		)
	)
	(label "A.CA5"
		(at 308.61 69.85 0)
		(effects
			(font
				(size 1.27 1.27)
			)
			(justify left bottom)
		)
	)
	(label "A.DQ23"
		(at 71.12 152.4 0)
		(effects
			(font
				(size 1.27 1.27)
			)
			(justify left bottom)
		)
	)
	(label "B.DQ24"
		(at 129.54 162.56 180)
		(effects
			(font
				(size 1.27 1.27)
			)
			(justify right bottom)
		)
	)
	(label "VSS_DET1"
		(at 254 234.95 0)
		(effects
			(font
				(size 1.27 1.27)
			)
			(justify left bottom)
		)
	)
	(label "B.DQ2"
		(at 129.54 68.58 180)
		(effects
			(font
				(size 1.27 1.27)
			)
			(justify right bottom)
		)
	)
	(label "CTRL.CK_P"
		(at 372.11 49.53 180)
		(effects
			(font
				(size 1.27 1.27)
			)
			(justify right bottom)
		)
	)
	(label "A.DQ31"
		(at 71.12 185.42 0)
		(effects
			(font
				(size 1.27 1.27)
			)
			(justify left bottom)
		)
	)
	(label "B.DQS1_N"
		(at 129.54 109.22 180)
		(effects
			(font
				(size 1.27 1.27)
			)
			(justify right bottom)
		)
	)
	(label "A.CS1_c"
		(at 308.61 80.01 0)
		(effects
			(font
				(size 1.27 1.27)
			)
			(justify left bottom)
		)
	)
	(label "A.DQS8_P"
		(at 71.12 187.96 0)
		(effects
			(font
				(size 1.27 1.27)
			)
			(justify left bottom)
		)
	)
	(label "A.CB7"
		(at 71.12 218.44 0)
		(effects
			(font
				(size 1.27 1.27)
			)
			(justify left bottom)
		)
	)
	(label "VIN_BULK"
		(at 313.69 36.83 0)
		(effects
			(font
				(size 1.27 1.27)
			)
			(justify left bottom)
		)
	)
	(label "B.DQS1_P"
		(at 129.54 106.68 180)
		(effects
			(font
				(size 1.27 1.27)
			)
			(justify right bottom)
		)
	)
	(label "A.DQ11"
		(at 71.12 104.14 0)
		(effects
			(font
				(size 1.27 1.27)
			)
			(justify left bottom)
		)
	)
	(label "A.CB5"
		(at 71.12 213.36 0)
		(effects
			(font
				(size 1.27 1.27)
			)
			(justify left bottom)
		)
	)
	(label "A.DQ26"
		(at 71.12 167.64 0)
		(effects
			(font
				(size 1.27 1.27)
			)
			(justify left bottom)
		)
	)
	(label "A.DQS4_P"
		(at 71.12 205.74 0)
		(effects
			(font
				(size 1.27 1.27)
			)
			(justify left bottom)
		)
	)
	(label "CTRL.~{ALERT}"
		(at 372.11 46.99 180)
		(effects
			(font
				(size 1.27 1.27)
			)
			(justify right bottom)
		)
	)
	(label "A.CS0_c"
		(at 308.61 77.47 0)
		(effects
			(font
				(size 1.27 1.27)
			)
			(justify left bottom)
		)
	)
	(label "A.DQ10"
		(at 71.12 101.6 0)
		(effects
			(font
				(size 1.27 1.27)
			)
			(justify left bottom)
		)
	)
	(label "A.CA4"
		(at 308.61 67.31 0)
		(effects
			(font
				(size 1.27 1.27)
			)
			(justify left bottom)
		)
	)
	(label "B.DQS9_P"
		(at 129.54 220.98 180)
		(effects
			(font
				(size 1.27 1.27)
			)
			(justify right bottom)
		)
	)
	(label "B.DQ22"
		(at 129.54 149.86 180)
		(effects
			(font
				(size 1.27 1.27)
			)
			(justify right bottom)
		)
	)
	(label "HSA"
		(at 240.03 264.16 0)
		(effects
			(font
				(size 1.27 1.27)
			)
			(justify left bottom)
		)
	)
	(label "B.CB1"
		(at 129.54 198.12 180)
		(effects
			(font
				(size 1.27 1.27)
			)
			(justify right bottom)
		)
	)
	(label "VIN_MGMT"
		(at 247.65 82.55 180)
		(effects
			(font
				(size 1.27 1.27)
			)
			(justify right bottom)
		)
	)
	(label "B.DQS5_P"
		(at 129.54 88.9 180)
		(effects
			(font
				(size 1.27 1.27)
			)
			(justify right bottom)
		)
	)
	(label "CTRL.DLBDQ"
		(at 308.61 46.99 0)
		(effects
			(font
				(size 1.27 1.27)
			)
			(justify left bottom)
		)
	)
	(label "B.DQ0"
		(at 129.54 63.5 180)
		(effects
			(font
				(size 1.27 1.27)
			)
			(justify right bottom)
		)
	)
	(label "A.DQ4"
		(at 71.12 78.74 0)
		(effects
			(font
				(size 1.27 1.27)
			)
			(justify left bottom)
		)
	)
	(label "B.CS1_c"
		(at 372.11 80.01 180)
		(effects
			(font
				(size 1.27 1.27)
			)
			(justify right bottom)
		)
	)
	(label "A.CA0"
		(at 308.61 57.15 0)
		(effects
			(font
				(size 1.27 1.27)
			)
			(justify left bottom)
		)
	)
	(label "B.CA1"
		(at 372.11 62.23 180)
		(effects
			(font
				(size 1.27 1.27)
			)
			(justify right bottom)
		)
	)
	(label "A.DQS7_P"
		(at 71.12 154.94 0)
		(effects
			(font
				(size 1.27 1.27)
			)
			(justify left bottom)
		)
	)
	(label "B.DQS7_N"
		(at 129.54 157.48 180)
		(effects
			(font
				(size 1.27 1.27)
			)
			(justify right bottom)
		)
	)
	(label "VSS_DET1"
		(at 314.96 90.17 0)
		(effects
			(font
				(size 1.27 1.27)
			)
			(justify left bottom)
		)
	)
	(label "B.DQ10"
		(at 129.54 101.6 180)
		(effects
			(font
				(size 1.27 1.27)
			)
			(justify right bottom)
		)
	)
	(label "B.DQS4_N"
		(at 129.54 208.28 180)
		(effects
			(font
				(size 1.27 1.27)
			)
			(justify right bottom)
		)
	)
	(label "A.DQS3_P"
		(at 71.12 172.72 0)
		(effects
			(font
				(size 1.27 1.27)
			)
			(justify left bottom)
		)
	)
	(label "A.DQ18"
		(at 71.12 134.62 0)
		(effects
			(font
				(size 1.27 1.27)
			)
			(justify left bottom)
		)
	)
	(label "A.DQ15"
		(at 71.12 119.38 0)
		(effects
			(font
				(size 1.27 1.27)
			)
			(justify left bottom)
		)
	)
	(label "B.CB2"
		(at 129.54 200.66 180)
		(effects
			(font
				(size 1.27 1.27)
			)
			(justify right bottom)
		)
	)
	(label "A.DQ0"
		(at 71.12 63.5 0)
		(effects
			(font
				(size 1.27 1.27)
			)
			(justify left bottom)
		)
	)
	(label "B.DQS3_P"
		(at 129.54 172.72 180)
		(effects
			(font
				(size 1.27 1.27)
			)
			(justify right bottom)
		)
	)
	(label "A.DQ1"
		(at 71.12 66.04 0)
		(effects
			(font
				(size 1.27 1.27)
			)
			(justify left bottom)
		)
	)
	(label "A.DQS8_N"
		(at 71.12 190.5 0)
		(effects
			(font
				(size 1.27 1.27)
			)
			(justify left bottom)
		)
	)
	(label "B.DQ25"
		(at 129.54 165.1 180)
		(effects
			(font
				(size 1.27 1.27)
			)
			(justify right bottom)
		)
	)
	(label "CTRL.~{RESET}"
		(at 308.61 52.07 0)
		(effects
			(font
				(size 1.27 1.27)
			)
			(justify left bottom)
		)
	)
	(label "B.DQ31"
		(at 129.54 185.42 180)
		(effects
			(font
				(size 1.27 1.27)
			)
			(justify right bottom)
		)
	)
	(label "A.PAR"
		(at 308.61 74.93 0)
		(effects
			(font
				(size 1.27 1.27)
			)
			(justify left bottom)
		)
	)
	(label "B.DQ19"
		(at 129.54 137.16 180)
		(effects
			(font
				(size 1.27 1.27)
			)
			(justify right bottom)
		)
	)
	(label "B.DQ14"
		(at 129.54 116.84 180)
		(effects
			(font
				(size 1.27 1.27)
			)
			(justify right bottom)
		)
	)
	(label "A.DQ21"
		(at 71.12 147.32 0)
		(effects
			(font
				(size 1.27 1.27)
			)
			(justify left bottom)
		)
	)
	(label "B.CA6"
		(at 372.11 72.39 180)
		(effects
			(font
				(size 1.27 1.27)
			)
			(justify right bottom)
		)
	)
	(label "A.DQS1_N"
		(at 71.12 109.22 0)
		(effects
			(font
				(size 1.27 1.27)
			)
			(justify left bottom)
		)
	)
	(label "A.DQ19"
		(at 71.12 137.16 0)
		(effects
			(font
				(size 1.27 1.27)
			)
			(justify left bottom)
		)
	)
	(label "B.DQ28"
		(at 129.54 177.8 180)
		(effects
			(font
				(size 1.27 1.27)
			)
			(justify right bottom)
		)
	)
	(label "HSA"
		(at 372.11 36.83 180)
		(effects
			(font
				(size 1.27 1.27)
			)
			(justify right bottom)
		)
	)
	(label "B.CA3"
		(at 372.11 64.77 180)
		(effects
			(font
				(size 1.27 1.27)
			)
			(justify right bottom)
		)
	)
	(label "B.CB5"
		(at 129.54 213.36 180)
		(effects
			(font
				(size 1.27 1.27)
			)
			(justify right bottom)
		)
	)
	(label "A.DQS9_N"
		(at 71.12 223.52 0)
		(effects
			(font
				(size 1.27 1.27)
			)
			(justify left bottom)
		)
	)
	(label "A.DQ9"
		(at 71.12 99.06 0)
		(effects
			(font
				(size 1.27 1.27)
			)
			(justify left bottom)
		)
	)
	(label "DDR.SCL"
		(at 372.11 41.91 180)
		(effects
			(font
				(size 1.27 1.27)
			)
			(justify right bottom)
		)
	)
	(label "B.DQS6_N"
		(at 129.54 124.46 180)
		(effects
			(font
				(size 1.27 1.27)
			)
			(justify right bottom)
		)
	)
	(label "A.CA3"
		(at 308.61 64.77 0)
		(effects
			(font
				(size 1.27 1.27)
			)
			(justify left bottom)
		)
	)
	(label "B.CS0_c"
		(at 372.11 77.47 180)
		(effects
			(font
				(size 1.27 1.27)
			)
			(justify right bottom)
		)
	)
	(label "VIN_MGMT"
		(at 313.69 39.37 0)
		(effects
			(font
				(size 1.27 1.27)
			)
			(justify left bottom)
		)
	)
	(label "B.DQ15"
		(at 129.54 119.38 180)
		(effects
			(font
				(size 1.27 1.27)
			)
			(justify right bottom)
		)
	)
	(label "A.DQ8"
		(at 71.12 96.52 0)
		(effects
			(font
				(size 1.27 1.27)
			)
			(justify left bottom)
		)
	)
	(label "A.CB6"
		(at 71.12 215.9 0)
		(effects
			(font
				(size 1.27 1.27)
			)
			(justify left bottom)
		)
	)
	(label "A.DQ7"
		(at 71.12 86.36 0)
		(effects
			(font
				(size 1.27 1.27)
			)
			(justify left bottom)
		)
	)
	(label "A.DQS5_N"
		(at 71.12 91.44 0)
		(effects
			(font
				(size 1.27 1.27)
			)
			(justify left bottom)
		)
	)
	(label "A.DQ13"
		(at 71.12 114.3 0)
		(effects
			(font
				(size 1.27 1.27)
			)
			(justify left bottom)
		)
	)
	(label "A.DQ17"
		(at 71.12 132.08 0)
		(effects
			(font
				(size 1.27 1.27)
			)
			(justify left bottom)
		)
	)
	(label "B.DQ12"
		(at 129.54 111.76 180)
		(effects
			(font
				(size 1.27 1.27)
			)
			(justify right bottom)
		)
	)
	(label "B.DQS2_P"
		(at 129.54 139.7 180)
		(effects
			(font
				(size 1.27 1.27)
			)
			(justify right bottom)
		)
	)
	(label "A.CA6"
		(at 308.61 72.39 0)
		(effects
			(font
				(size 1.27 1.27)
			)
			(justify left bottom)
		)
	)
	(label "B.CA2"
		(at 372.11 59.69 180)
		(effects
			(font
				(size 1.27 1.27)
			)
			(justify right bottom)
		)
	)
	(label "B.DQ1"
		(at 129.54 66.04 180)
		(effects
			(font
				(size 1.27 1.27)
			)
			(justify right bottom)
		)
	)
	(label "B.DQS8_N"
		(at 129.54 190.5 180)
		(effects
			(font
				(size 1.27 1.27)
			)
			(justify right bottom)
		)
	)
	(label "B.DQ13"
		(at 129.54 114.3 180)
		(effects
			(font
				(size 1.27 1.27)
			)
			(justify right bottom)
		)
	)
	(label "A.DQS4_N"
		(at 71.12 208.28 0)
		(effects
			(font
				(size 1.27 1.27)
			)
			(justify left bottom)
		)
	)
	(label "B.DQ16"
		(at 129.54 129.54 180)
		(effects
			(font
				(size 1.27 1.27)
			)
			(justify right bottom)
		)
	)
	(label "CTRL.DLBDQS"
		(at 308.61 49.53 0)
		(effects
			(font
				(size 1.27 1.27)
			)
			(justify left bottom)
		)
	)
	(label "B.DQ27"
		(at 129.54 170.18 180)
		(effects
			(font
				(size 1.27 1.27)
			)
			(justify right bottom)
		)
	)
	(label "A.CB0"
		(at 71.12 195.58 0)
		(effects
			(font
				(size 1.27 1.27)
			)
			(justify left bottom)
		)
	)
	(label "A.DQ29"
		(at 71.12 180.34 0)
		(effects
			(font
				(size 1.27 1.27)
			)
			(justify left bottom)
		)
	)
	(label "A.DQS9_P"
		(at 71.12 220.98 0)
		(effects
			(font
				(size 1.27 1.27)
			)
			(justify left bottom)
		)
	)
	(label "B.CB7"
		(at 129.54 218.44 180)
		(effects
			(font
				(size 1.27 1.27)
			)
			(justify right bottom)
		)
	)
	(label "DDR.SDA"
		(at 372.11 39.37 180)
		(effects
			(font
				(size 1.27 1.27)
			)
			(justify right bottom)
		)
	)
	(label "CTRL.CK_N"
		(at 372.11 52.07 180)
		(effects
			(font
				(size 1.27 1.27)
			)
			(justify right bottom)
		)
	)
	(label "B.DQS9_N"
		(at 129.54 223.52 180)
		(effects
			(font
				(size 1.27 1.27)
			)
			(justify right bottom)
		)
	)
	(label "B.DQ29"
		(at 129.54 180.34 180)
		(effects
			(font
				(size 1.27 1.27)
			)
			(justify right bottom)
		)
	)
	(label "A.DQS2_N"
		(at 71.12 142.24 0)
		(effects
			(font
				(size 1.27 1.27)
			)
			(justify left bottom)
		)
	)
	(label "CTRL.PWR_GOOD"
		(at 308.61 41.91 0)
		(effects
			(font
				(size 1.27 1.27)
			)
			(justify left bottom)
		)
	)
	(label "B.CB4"
		(at 129.54 210.82 180)
		(effects
			(font
				(size 1.27 1.27)
			)
			(justify right bottom)
		)
	)
	(label "A.DQS3_N"
		(at 71.12 175.26 0)
		(effects
			(font
				(size 1.27 1.27)
			)
			(justify left bottom)
		)
	)
	(label "A.DQ30"
		(at 71.12 182.88 0)
		(effects
			(font
				(size 1.27 1.27)
			)
			(justify left bottom)
		)
	)
	(label "B.DQ5"
		(at 129.54 81.28 180)
		(effects
			(font
				(size 1.27 1.27)
			)
			(justify right bottom)
		)
	)
	(label "B.DQS5_N"
		(at 129.54 91.44 180)
		(effects
			(font
				(size 1.27 1.27)
			)
			(justify right bottom)
		)
	)
	(label "A.CB3"
		(at 71.12 203.2 0)
		(effects
			(font
				(size 1.27 1.27)
			)
			(justify left bottom)
		)
	)
	(label "B.DQ30"
		(at 129.54 182.88 180)
		(effects
			(font
				(size 1.27 1.27)
			)
			(justify right bottom)
		)
	)
	(label "A.DQ22"
		(at 71.12 149.86 0)
		(effects
			(font
				(size 1.27 1.27)
			)
			(justify left bottom)
		)
	)
	(label "B.CA0"
		(at 372.11 57.15 180)
		(effects
			(font
				(size 1.27 1.27)
			)
			(justify right bottom)
		)
	)
	(label "A.CA2"
		(at 308.61 62.23 0)
		(effects
			(font
				(size 1.27 1.27)
			)
			(justify left bottom)
		)
	)
	(label "B.DQ3"
		(at 129.54 71.12 180)
		(effects
			(font
				(size 1.27 1.27)
			)
			(justify right bottom)
		)
	)
	(label "A.DQ16"
		(at 71.12 129.54 0)
		(effects
			(font
				(size 1.27 1.27)
			)
			(justify left bottom)
		)
	)
	(label "A.DQS1_P"
		(at 71.12 106.68 0)
		(effects
			(font
				(size 1.27 1.27)
			)
			(justify left bottom)
		)
	)
	(label "B.DQS2_N"
		(at 129.54 142.24 180)
		(effects
			(font
				(size 1.27 1.27)
			)
			(justify right bottom)
		)
	)
	(label "B.DQS0_P"
		(at 129.54 73.66 180)
		(effects
			(font
				(size 1.27 1.27)
			)
			(justify right bottom)
		)
	)
	(label "B.DQS6_P"
		(at 129.54 121.92 180)
		(effects
			(font
				(size 1.27 1.27)
			)
			(justify right bottom)
		)
	)
	(label "B.DQ4"
		(at 129.54 78.74 180)
		(effects
			(font
				(size 1.27 1.27)
			)
			(justify right bottom)
		)
	)
	(label "B.DQ9"
		(at 129.54 99.06 180)
		(effects
			(font
				(size 1.27 1.27)
			)
			(justify right bottom)
		)
	)
	(label "A.DQS5_P"
		(at 71.12 88.9 0)
		(effects
			(font
				(size 1.27 1.27)
			)
			(justify left bottom)
		)
	)
	(label "A.DQ27"
		(at 71.12 170.18 0)
		(effects
			(font
				(size 1.27 1.27)
			)
			(justify left bottom)
		)
	)
	(label "A.DQS7_N"
		(at 71.12 157.48 0)
		(effects
			(font
				(size 1.27 1.27)
			)
			(justify left bottom)
		)
	)
	(label "A.DQ6"
		(at 71.12 83.82 0)
		(effects
			(font
				(size 1.27 1.27)
			)
			(justify left bottom)
		)
	)
	(label "A.DQS0_P"
		(at 71.12 73.66 0)
		(effects
			(font
				(size 1.27 1.27)
			)
			(justify left bottom)
		)
	)
	(label "B.DQS3_N"
		(at 129.54 175.26 180)
		(effects
			(font
				(size 1.27 1.27)
			)
			(justify right bottom)
		)
	)
	(label "A.CB4"
		(at 71.12 210.82 0)
		(effects
			(font
				(size 1.27 1.27)
			)
			(justify left bottom)
		)
	)
	(label "A.DQ3"
		(at 71.12 71.12 0)
		(effects
			(font
				(size 1.27 1.27)
			)
			(justify left bottom)
		)
	)
	(label "B.CB0"
		(at 129.54 195.58 180)
		(effects
			(font
				(size 1.27 1.27)
			)
			(justify right bottom)
		)
	)
	(label "B.CA4"
		(at 372.11 67.31 180)
		(effects
			(font
				(size 1.27 1.27)
			)
			(justify right bottom)
		)
	)
	(label "B.DQ21"
		(at 129.54 147.32 180)
		(effects
			(font
				(size 1.27 1.27)
			)
			(justify right bottom)
		)
	)
	(label "A.DQ5"
		(at 71.12 81.28 0)
		(effects
			(font
				(size 1.27 1.27)
			)
			(justify left bottom)
		)
	)
	(label "A.DQ25"
		(at 71.12 165.1 0)
		(effects
			(font
				(size 1.27 1.27)
			)
			(justify left bottom)
		)
	)
	(label "B.DQ17"
		(at 129.54 132.08 180)
		(effects
			(font
				(size 1.27 1.27)
			)
			(justify right bottom)
		)
	)
	(label "B.DQS4_P"
		(at 129.54 205.74 180)
		(effects
			(font
				(size 1.27 1.27)
			)
			(justify right bottom)
		)
	)
	(label "B.DQS0_N"
		(at 129.54 76.2 180)
		(effects
			(font
				(size 1.27 1.27)
			)
			(justify right bottom)
		)
	)
	(label "VIN_BULK"
		(at 271.78 92.71 0)
		(effects
			(font
				(size 1.27 1.27)
			)
			(justify left bottom)
		)
	)
	(label "A.DQS6_N"
		(at 71.12 124.46 0)
		(effects
			(font
				(size 1.27 1.27)
			)
			(justify left bottom)
		)
	)
	(label "A.CA1"
		(at 308.61 59.69 0)
		(effects
			(font
				(size 1.27 1.27)
			)
			(justify left bottom)
		)
	)
	(label "A.DQ28"
		(at 71.12 177.8 0)
		(effects
			(font
				(size 1.27 1.27)
			)
			(justify left bottom)
		)
	)
	(label "B.DQ7"
		(at 129.54 86.36 180)
		(effects
			(font
				(size 1.27 1.27)
			)
			(justify right bottom)
		)
	)
	(label "B.CA5"
		(at 372.11 69.85 180)
		(effects
			(font
				(size 1.27 1.27)
			)
			(justify right bottom)
		)
	)
	(label "A.DQ20"
		(at 71.12 144.78 0)
		(effects
			(font
				(size 1.27 1.27)
			)
			(justify left bottom)
		)
	)
	(label "B.DQ26"
		(at 129.54 167.64 180)
		(effects
			(font
				(size 1.27 1.27)
			)
			(justify right bottom)
		)
	)
	(label "B.DQ6"
		(at 129.54 83.82 180)
		(effects
			(font
				(size 1.27 1.27)
			)
			(justify right bottom)
		)
	)
	(label "VIN_MGMT"
		(at 271.78 109.22 0)
		(effects
			(font
				(size 1.27 1.27)
			)
			(justify left bottom)
		)
	)
	(label "B.CB3"
		(at 129.54 203.2 180)
		(effects
			(font
				(size 1.27 1.27)
			)
			(justify right bottom)
		)
	)
	(label "VIN_BULK"
		(at 238.76 33.02 0)
		(effects
			(font
				(size 1.27 1.27)
			)
			(justify left bottom)
		)
	)
	(label "B.DQ8"
		(at 129.54 96.52 180)
		(effects
			(font
				(size 1.27 1.27)
			)
			(justify right bottom)
		)
	)
	(label "B.DQS8_P"
		(at 129.54 187.96 180)
		(effects
			(font
				(size 1.27 1.27)
			)
			(justify right bottom)
		)
	)
	(label "A.DQS2_P"
		(at 71.12 139.7 0)
		(effects
			(font
				(size 1.27 1.27)
			)
			(justify left bottom)
		)
	)
	(label "B.PAR"
		(at 372.11 74.93 180)
		(effects
			(font
				(size 1.27 1.27)
			)
			(justify right bottom)
		)
	)
	(label "B.DQS7_P"
		(at 129.54 154.94 180)
		(effects
			(font
				(size 1.27 1.27)
			)
			(justify right bottom)
		)
	)
	(label "B.DQ23"
		(at 129.54 152.4 180)
		(effects
			(font
				(size 1.27 1.27)
			)
			(justify right bottom)
		)
	)
	(label "B.DQ18"
		(at 129.54 134.62 180)
		(effects
			(font
				(size 1.27 1.27)
			)
			(justify right bottom)
		)
	)
	(label "A.DQS6_P"
		(at 71.12 121.92 0)
		(effects
			(font
				(size 1.27 1.27)
			)
			(justify left bottom)
		)
	)
	(label "A.CB2"
		(at 71.12 200.66 0)
		(effects
			(font
				(size 1.27 1.27)
			)
			(justify left bottom)
		)
	)
	(global_label "HOT_SWAP_YELLOW"
		(shape input)
		(at 242.57 196.85 180)
		(fields_autoplaced yes)
		(effects
			(font
				(size 1.27 1.27)
			)
			(justify right)
		)
		(property "Intersheetrefs" "${INTERSHEET_REFS}"
			(at 222.5868 196.7706 0)
			(effects
				(font
					(size 1.27 1.27)
				)
				(justify right)
			)
		)
	)
	(global_label "VIN_BULK_EN"
		(shape input)
		(at 214.63 52.07 180)
		(fields_autoplaced yes)
		(effects
			(font
				(size 1.27 1.27)
			)
			(justify right)
		)
		(property "Intersheetrefs" "${INTERSHEET_REFS}"
			(at 199.9618 52.07 0)
			(effects
				(font
					(size 1.27 1.27)
				)
				(justify right)
			)
		)
	)
	(global_label "HOT_SWAP_GREEN"
		(shape input)
		(at 242.57 186.69 180)
		(fields_autoplaced yes)
		(effects
			(font
				(size 1.27 1.27)
			)
			(justify right)
		)
		(property "Intersheetrefs" "${INTERSHEET_REFS}"
			(at 223.4939 186.6106 0)
			(effects
				(font
					(size 1.27 1.27)
				)
				(justify right)
			)
		)
	)
	(global_label "HOT_SWAP_RED"
		(shape input)
		(at 242.57 176.53 180)
		(fields_autoplaced yes)
		(effects
			(font
				(size 1.27 1.27)
			)
			(justify right)
		)
		(property "Intersheetrefs" "${INTERSHEET_REFS}"
			(at 225.9734 176.4506 0)
			(effects
				(font
					(size 1.27 1.27)
				)
				(justify right)
			)
		)
	)
	(global_label "VIN_MGMT_EN"
		(shape input)
		(at 214.63 102.87 180)
		(fields_autoplaced yes)
		(effects
			(font
				(size 1.27 1.27)
			)
			(justify right)
		)
		(property "Intersheetrefs" "${INTERSHEET_REFS}"
			(at 199.72 102.87 0)
			(effects
				(font
					(size 1.27 1.27)
				)
				(justify right)
			)
		)
	)
	(global_label "~{DDR_PRESENCE}"
		(shape input)
		(at 284.48 234.95 0)
		(fields_autoplaced yes)
		(effects
			(font
				(size 1.27 1.27)
			)
			(justify left)
		)
		(property "Intersheetrefs" "${INTERSHEET_REFS}"
			(at 301.379 234.8706 0)
			(effects
				(font
					(size 1.27 1.27)
				)
				(justify left)
			)
		)
	)
	(global_label "HOT_SWAP_BUTTON"
		(shape input)
		(at 364.49 168.91 0)
		(fields_autoplaced yes)
		(effects
			(font
				(size 1.27 1.27)
			)
			(justify left)
		)
		(property "Intersheetrefs" "${INTERSHEET_REFS}"
			(at 384.5942 168.8306 0)
			(effects
				(font
					(size 1.27 1.27)
				)
				(justify left)
			)
		)
	)
	(hierarchical_label "DDR{I^{2}C}"
		(shape bidirectional)
		(at 383.54 34.29 0)
		(effects
			(font
				(size 1.27 1.27)
			)
			(justify left)
		)
	)
	(hierarchical_label "B{DDR5_RDIMM}"
		(shape input)
		(at 382.27 52.07 0)
		(effects
			(font
				(size 1.27 1.27)
			)
			(justify left)
		)
	)
	(hierarchical_label "A{DDR5_RDIMM}"
		(shape input)
		(at 60.96 50.8 180)
		(effects
			(font
				(size 1.27 1.27)
			)
			(justify right)
		)
	)
	(hierarchical_label "CTRL{DDR5_RDIMM}"
		(shape input)
		(at 299.72 36.83 180)
		(effects
			(font
				(size 1.27 1.27)
			)
			(justify right)
		)
	)
	(hierarchical_label "CTRL{DDR5_RDIMM}"
		(shape input)
		(at 383.54 41.91 0)
		(effects
			(font
				(size 1.27 1.27)
			)
			(justify left)
		)
	)
	(hierarchical_label "A{DDR5_RDIMM}"
		(shape input)
		(at 298.45 52.07 180)
		(effects
			(font
				(size 1.27 1.27)
			)
			(justify right)
		)
	)
	(hierarchical_label "B{DDR5_RDIMM}"
		(shape input)
		(at 139.7 50.8 0)
		(effects
			(font
				(size 1.27 1.27)
			)
			(justify left)
		)
	)
	(symbol
		(lib_id "antmicroCapacitors0603:C_10u_25V_0603")
		(at 281.94 99.06 90)
		(unit 1)
		(exclude_from_sim no)
		(in_bom yes)
		(on_board yes)
		(dnp no)
		(fields_autoplaced yes)
		(property "Reference" "C7"
			(at 284.48 95.2436 90)
			(effects
				(font
					(size 1.27 1.27)
					(thickness 0.15)
				)
				(justify right)
			)
		)
		(property "Value" "C_10u_25V_0603"
			(at 292.1 78.74 0)
			(effects
				(font
					(size 1.27 1.27)
					(thickness 0.15)
				)
				(justify left bottom)
				(hide yes)
			)
		)
		(property "Footprint" "antmicro-footprints:C_0603_1608Metric"
			(at 294.64 78.74 0)
			(effects
				(font
					(size 1.27 1.27)
					(thickness 0.15)
				)
				(justify left bottom)
				(hide yes)
			)
		)
		(property "Datasheet" "https://product.tdk.com/en/search/capacitor/ceramic/mlcc/info?part_no=C1608X5R1E106M080AC"
			(at 297.18 78.74 0)
			(effects
				(font
					(size 1.27 1.27)
					(thickness 0.15)
				)
				(justify left bottom)
				(hide yes)
			)
		)
		(property "Description" ""
			(at 281.94 99.06 0)
			(effects
				(font
					(size 1.27 1.27)
				)
				(hide yes)
			)
		)
		(property "MPN" "C1608X5R1E106M080AC"
			(at 299.72 78.74 0)
			(effects
				(font
					(size 1.27 1.27)
					(thickness 0.15)
				)
				(justify left bottom)
				(hide yes)
			)
		)
		(property "Manufacturer" "TDK"
			(at 302.26 78.74 0)
			(effects
				(font
					(size 1.27 1.27)
					(thickness 0.15)
				)
				(justify left bottom)
				(hide yes)
			)
		)
		(property "License" "Apache-2.0"
			(at 304.8 78.74 0)
			(effects
				(font
					(size 1.27 1.27)
					(thickness 0.15)
				)
				(justify left bottom)
				(hide yes)
			)
		)
		(property "Author" "Antmicro"
			(at 307.34 78.74 0)
			(effects
				(font
					(size 1.27 1.27)
					(thickness 0.15)
				)
				(justify left bottom)
				(hide yes)
			)
		)
		(property "Val" "10u"
			(at 284.48 97.7836 90)
			(effects
				(font
					(size 1.27 1.27)
					(thickness 0.15)
				)
				(justify right)
			)
		)
		(property "Voltage" "25V"
			(at 309.88 78.74 0)
			(effects
				(font
					(size 1.27 1.27)
				)
				(justify left bottom)
				(hide yes)
			)
		)
		(property "Dielectric" ""
			(at 312.42 78.74 0)
			(effects
				(font
					(size 1.27 1.27)
				)
				(justify left bottom)
				(hide yes)
			)
		)
		(pin "2"
		)
		(pin "1"
		)
		(instances
			(project "data-center-rdimm-ddr5-tester"
				(path ""
					(reference "C7")
					(unit 1)
				)
			)
		)
	)
	(symbol
		(lib_id "antmicroResistors0402:R_330R_0402")
		(at 288.29 161.29 270)
		(unit 1)
		(exclude_from_sim no)
		(in_bom yes)
		(on_board yes)
		(dnp no)
		(fields_autoplaced yes)
		(property "Reference" "R63"
			(at 290.83 162.56 90)
			(effects
				(font
					(size 1.27 1.27)
				)
				(justify left)
			)
		)
		(property "Value" "R_330R_0402"
			(at 275.59 181.61 0)
			(effects
				(font
					(size 1.27 1.27)
					(thickness 0.15)
				)
				(justify left bottom)
				(hide yes)
			)
		)
		(property "Footprint" "antmicro-footprints:R_0402_1005Metric"
			(at 273.05 181.61 0)
			(effects
				(font
					(size 1.27 1.27)
					(thickness 0.15)
				)
				(justify left bottom)
				(hide yes)
			)
		)
		(property "Datasheet" "https://www.bourns.com/docs/product-datasheets/cr.pdf"
			(at 270.51 181.61 0)
			(effects
				(font
					(size 1.27 1.27)
					(thickness 0.15)
				)
				(justify left bottom)
				(hide yes)
			)
		)
		(property "Description" ""
			(at 288.29 161.29 0)
			(effects
				(font
					(size 1.27 1.27)
				)
				(hide yes)
			)
		)
		(property "Manufacturer" "Bourns"
			(at 265.43 181.61 0)
			(effects
				(font
					(size 1.27 1.27)
					(thickness 0.15)
				)
				(justify left bottom)
				(hide yes)
			)
		)
		(property "MPN" "CR0402-FX-3300GLF"
			(at 267.97 181.61 0)
			(effects
				(font
					(size 1.27 1.27)
					(thickness 0.15)
				)
				(justify left bottom)
				(hide yes)
			)
		)
		(property "Val" "330R"
			(at 290.83 165.7349 90)
			(effects
				(font
					(size 1.27 1.27)
					(thickness 0.15)
				)
				(justify left)
			)
		)
		(property "License" "Apache-2.0"
			(at 262.89 181.61 0)
			(effects
				(font
					(size 1.27 1.27)
					(thickness 0.15)
				)
				(justify left bottom)
				(hide yes)
			)
		)
		(property "Author" "Antmicro"
			(at 260.35 181.61 0)
			(effects
				(font
					(size 1.27 1.27)
					(thickness 0.15)
				)
				(justify left bottom)
				(hide yes)
			)
		)
		(property "Tolerance" "1%"
			(at 278.13 181.61 0)
			(effects
				(font
					(size 1.27 1.27)
				)
				(justify left bottom)
				(hide yes)
			)
		)
		(pin "1"
		)
		(pin "2"
		)
		(instances
			(project "data-center-rdimm-ddr5-tester"
				(path ""
					(reference "R63")
					(unit 1)
				)
			)
		)
	)
	(symbol
		(lib_id "antmicropower:+3V3")
		(at 220.98 153.67 0)
		(unit 1)
		(exclude_from_sim no)
		(in_bom yes)
		(on_board yes)
		(dnp no)
		(property "Reference" "#PWR0199"
			(at 220.98 157.48 0)
			(effects
				(font
					(size 1.27 1.27)
				)
				(hide yes)
			)
		)
		(property "Value" "+3V3"
			(at 217.805 151.13 0)
			(effects
				(font
					(size 1.27 1.27)
					(thickness 0.15)
				)
				(justify left bottom)
			)
		)
		(property "Footprint" ""
			(at 236.22 161.29 0)
			(effects
				(font
					(size 1.27 1.27)
					(thickness 0.15)
				)
				(justify left bottom)
				(hide yes)
			)
		)
		(property "Datasheet" ""
			(at 236.22 163.83 0)
			(effects
				(font
					(size 1.27 1.27)
					(thickness 0.15)
				)
				(justify left bottom)
				(hide yes)
			)
		)
		(property "Description" ""
			(at 220.98 153.67 0)
			(effects
				(font
					(size 1.27 1.27)
				)
				(hide yes)
			)
		)
		(property "Author" "Antmicro"
			(at 236.22 156.21 0)
			(effects
				(font
					(size 1.27 1.27)
					(thickness 0.15)
				)
				(justify left bottom)
				(hide yes)
			)
		)
		(property "License" "Apache-2.0"
			(at 236.22 158.75 0)
			(effects
				(font
					(size 1.27 1.27)
					(thickness 0.15)
				)
				(justify left bottom)
				(hide yes)
			)
		)
		(pin "1"
		)
		(instances
			(project "data-center-rdimm-ddr5-tester"
				(path ""
					(reference "#PWR0199")
					(unit 1)
				)
			)
		)
	)
	(symbol
		(lib_id "antmicropower:GND")
		(at 374.65 240.03 0)
		(unit 1)
		(exclude_from_sim no)
		(in_bom yes)
		(on_board yes)
		(dnp no)
		(fields_autoplaced yes)
		(property "Reference" "#PWR049"
			(at 374.65 246.38 0)
			(effects
				(font
					(size 1.27 1.27)
				)
				(hide yes)
			)
		)
		(property "Value" "GND"
			(at 372.745 244.475 0)
			(effects
				(font
					(size 1.27 1.27)
					(thickness 0.15)
				)
				(justify left bottom)
			)
		)
		(property "Footprint" ""
			(at 383.54 247.65 0)
			(effects
				(font
					(size 1.27 1.27)
					(thickness 0.15)
				)
				(justify left bottom)
				(hide yes)
			)
		)
		(property "Datasheet" ""
			(at 383.54 252.73 0)
			(effects
				(font
					(size 1.27 1.27)
					(thickness 0.15)
				)
				(justify left bottom)
				(hide yes)
			)
		)
		(property "Description" ""
			(at 374.65 240.03 0)
			(effects
				(font
					(size 1.27 1.27)
				)
				(hide yes)
			)
		)
		(property "Author" "Antmicro"
			(at 383.54 245.11 0)
			(effects
				(font
					(size 1.27 1.27)
					(thickness 0.15)
				)
				(justify left bottom)
				(hide yes)
			)
		)
		(property "License" "Apache-2.0"
			(at 383.54 247.65 0)
			(effects
				(font
					(size 1.27 1.27)
					(thickness 0.15)
				)
				(justify left bottom)
				(hide yes)
			)
		)
		(pin "1"
		)
		(instances
			(project "data-center-rdimm-ddr5-tester"
				(path ""
					(reference "#PWR049")
					(unit 1)
				)
			)
		)
	)
	(symbol
		(lib_id "antmicroResistors0402:R_0R_0402")
		(at 275.59 234.95 0)
		(unit 1)
		(exclude_from_sim no)
		(in_bom yes)
		(on_board yes)
		(dnp no)
		(property "Reference" "R27"
			(at 281.94 233.68 0)
			(effects
				(font
					(size 1.27 1.27)
					(thickness 0.15)
				)
			)
		)
		(property "Value" "R_0R_0402"
			(at 295.91 247.65 0)
			(effects
				(font
					(size 1.27 1.27)
					(thickness 0.15)
				)
				(justify left bottom)
				(hide yes)
			)
		)
		(property "Footprint" "antmicro-footprints:R_0402_1005Metric"
			(at 295.91 250.19 0)
			(effects
				(font
					(size 1.27 1.27)
					(thickness 0.15)
				)
				(justify left bottom)
				(hide yes)
			)
		)
		(property "Datasheet" "https://industrial.panasonic.com/cdbs/www-data/pdf/RDA0000/AOA0000C301.pdf"
			(at 295.91 252.73 0)
			(effects
				(font
					(size 1.27 1.27)
					(thickness 0.15)
				)
				(justify left bottom)
				(hide yes)
			)
		)
		(property "Description" ""
			(at 275.59 234.95 0)
			(effects
				(font
					(size 1.27 1.27)
				)
				(hide yes)
			)
		)
		(property "MPN" "ERJ2GE0R00X"
			(at 295.91 255.27 0)
			(effects
				(font
					(size 1.27 1.27)
					(thickness 0.15)
				)
				(justify left bottom)
				(hide yes)
			)
		)
		(property "Manufacturer" "Panasonic"
			(at 295.91 257.81 0)
			(effects
				(font
					(size 1.27 1.27)
					(thickness 0.15)
				)
				(justify left bottom)
				(hide yes)
			)
		)
		(property "License" "Apache-2.0"
			(at 295.91 260.35 0)
			(effects
				(font
					(size 1.27 1.27)
					(thickness 0.15)
				)
				(justify left bottom)
				(hide yes)
			)
		)
		(property "Author" "Antmicro"
			(at 295.91 262.89 0)
			(effects
				(font
					(size 1.27 1.27)
					(thickness 0.15)
				)
				(justify left bottom)
				(hide yes)
			)
		)
		(property "Val" "0R"
			(at 274.32 233.68 0)
			(effects
				(font
					(size 1.27 1.27)
					(thickness 0.15)
				)
			)
		)
		(property "Tolerance" "~"
			(at 295.91 245.11 0)
			(effects
				(font
					(size 1.27 1.27)
				)
				(justify left bottom)
				(hide yes)
			)
		)
		(property "Current" "1A"
			(at 295.91 265.43 0)
			(effects
				(font
					(size 1.27 1.27)
					(thickness 0.15)
				)
				(justify left bottom)
				(hide yes)
			)
		)
		(pin "1"
		)
		(pin "2"
		)
		(instances
			(project "data-center-rdimm-ddr5-tester"
				(path ""
					(reference "R27")
					(unit 1)
				)
			)
		)
	)
	(symbol
		(lib_id "antmicroResistors0402:R_47k_0402")
		(at 215.9 109.22 90)
		(unit 1)
		(exclude_from_sim no)
		(in_bom yes)
		(on_board yes)
		(dnp no)
		(fields_autoplaced yes)
		(property "Reference" "R245"
			(at 218.44 105.41 90)
			(effects
				(font
					(size 1.27 1.27)
					(thickness 0.15)
				)
				(justify right)
			)
		)
		(property "Value" "R_47k_0402"
			(at 228.6 88.9 0)
			(effects
				(font
					(size 1.27 1.27)
					(thickness 0.15)
				)
				(justify left bottom)
				(hide yes)
			)
		)
		(property "Footprint" "antmicro-footprints:R_0402_1005Metric"
			(at 231.14 88.9 0)
			(effects
				(font
					(size 1.27 1.27)
					(thickness 0.15)
				)
				(justify left bottom)
				(hide yes)
			)
		)
		(property "Datasheet" "https://www.bourns.com/docs/product-datasheets/cr.pdf"
			(at 233.68 88.9 0)
			(effects
				(font
					(size 1.27 1.27)
					(thickness 0.15)
				)
				(justify left bottom)
				(hide yes)
			)
		)
		(property "Description" ""
			(at 215.9 109.22 0)
			(effects
				(font
					(size 1.27 1.27)
				)
				(hide yes)
			)
		)
		(property "MPN" "CR0402-FX-4702GLF"
			(at 236.22 88.9 0)
			(effects
				(font
					(size 1.27 1.27)
					(thickness 0.15)
				)
				(justify left bottom)
				(hide yes)
			)
		)
		(property "Manufacturer" "Bourns"
			(at 238.76 88.9 0)
			(effects
				(font
					(size 1.27 1.27)
					(thickness 0.15)
				)
				(justify left bottom)
				(hide yes)
			)
		)
		(property "License" "Apache-2.0"
			(at 241.3 88.9 0)
			(effects
				(font
					(size 1.27 1.27)
					(thickness 0.15)
				)
				(justify left bottom)
				(hide yes)
			)
		)
		(property "Author" "Antmicro"
			(at 243.84 88.9 0)
			(effects
				(font
					(size 1.27 1.27)
					(thickness 0.15)
				)
				(justify left bottom)
				(hide yes)
			)
		)
		(property "Val" "47k"
			(at 218.44 107.95 90)
			(effects
				(font
					(size 1.27 1.27)
					(thickness 0.15)
				)
				(justify right)
			)
		)
		(property "Tolerance" "1%"
			(at 226.06 88.9 0)
			(effects
				(font
					(size 1.27 1.27)
				)
				(justify left bottom)
				(hide yes)
			)
		)
		(pin "2"
		)
		(pin "1"
		)
		(instances
			(project "data-center-rdimm-ddr5-tester"
				(path ""
					(reference "R245")
					(unit 1)
				)
			)
		)
	)
	(symbol
		(lib_id "antmicroCapacitors0402:C_100n_0402")
		(at 271.78 115.57 90)
		(unit 1)
		(exclude_from_sim no)
		(in_bom yes)
		(on_board yes)
		(dnp no)
		(fields_autoplaced yes)
		(property "Reference" "C317"
			(at 274.955 111.7535 90)
			(effects
				(font
					(size 1.27 1.27)
					(thickness 0.15)
				)
				(justify right)
			)
		)
		(property "Value" "C_100n_0402"
			(at 281.94 95.25 0)
			(effects
				(font
					(size 1.27 1.27)
					(thickness 0.15)
				)
				(justify left bottom)
				(hide yes)
			)
		)
		(property "Footprint" "antmicro-footprints:C_0402_1005Metric"
			(at 284.48 95.25 0)
			(effects
				(font
					(size 1.27 1.27)
					(thickness 0.15)
				)
				(justify left bottom)
				(hide yes)
			)
		)
		(property "Datasheet" "https://www.murata.com/products/productdetail?partno=GRM155R61H104KE14%23"
			(at 287.02 95.25 0)
			(effects
				(font
					(size 1.27 1.27)
					(thickness 0.15)
				)
				(justify left bottom)
				(hide yes)
			)
		)
		(property "Description" ""
			(at 271.78 115.57 0)
			(effects
				(font
					(size 1.27 1.27)
				)
				(hide yes)
			)
		)
		(property "MPN" "GRM155R61H104KE14D"
			(at 289.56 95.25 0)
			(effects
				(font
					(size 1.27 1.27)
					(thickness 0.15)
				)
				(justify left bottom)
				(hide yes)
			)
		)
		(property "Manufacturer" "Murata"
			(at 292.1 95.25 0)
			(effects
				(font
					(size 1.27 1.27)
					(thickness 0.15)
				)
				(justify left bottom)
				(hide yes)
			)
		)
		(property "License" "Apache-2.0"
			(at 294.64 95.25 0)
			(effects
				(font
					(size 1.27 1.27)
					(thickness 0.15)
				)
				(justify left bottom)
				(hide yes)
			)
		)
		(property "Author" "Antmicro"
			(at 297.18 95.25 0)
			(effects
				(font
					(size 1.27 1.27)
					(thickness 0.15)
				)
				(justify left bottom)
				(hide yes)
			)
		)
		(property "Val" "100n"
			(at 274.955 114.2935 90)
			(effects
				(font
					(size 1.27 1.27)
					(thickness 0.15)
				)
				(justify right)
			)
		)
		(property "Voltage" "50V"
			(at 299.72 95.25 0)
			(effects
				(font
					(size 1.27 1.27)
				)
				(justify left bottom)
				(hide yes)
			)
		)
		(property "Dielectric" "X5R"
			(at 302.26 95.25 0)
			(effects
				(font
					(size 1.27 1.27)
				)
				(justify left bottom)
				(hide yes)
			)
		)
		(pin "1"
		)
		(pin "2"
		)
		(instances
			(project "data-center-rdimm-ddr5-tester"
				(path ""
					(reference "C317")
					(unit 1)
				)
			)
		)
	)
	(symbol
		(lib_id "antmicroTransistorsFETsMOSFETsSingle:SI7613DN-T1-GE3")
		(at 226.06 90.17 270)
		(mirror x)
		(unit 1)
		(exclude_from_sim no)
		(in_bom yes)
		(on_board yes)
		(dnp no)
		(property "Reference" "Q27"
			(at 228.6 76.2 90)
			(effects
				(font
					(size 1.27 1.27)
					(thickness 0.15)
				)
			)
		)
		(property "Value" "SI7613DN-T1-GE3"
			(at 228.6 74.93 0)
			(effects
				(font
					(size 1.27 1.27)
					(thickness 0.15)
				)
				(justify left bottom)
				(hide yes)
			)
		)
		(property "Footprint" "antmicro-footprints:Vishay_PowerPAK_1212-8_Single"
			(at 227.33 74.93 0)
			(effects
				(font
					(size 1.27 1.27)
					(thickness 0.15)
				)
				(justify left bottom)
				(hide yes)
			)
		)
		(property "Datasheet" "https://www.vishay.com/docs/64809/si7613dn.pdf"
			(at 224.79 74.93 0)
			(effects
				(font
					(size 1.27 1.27)
					(thickness 0.15)
				)
				(justify left bottom)
				(hide yes)
			)
		)
		(property "Description" ""
			(at 226.06 90.17 0)
			(effects
				(font
					(size 1.27 1.27)
				)
				(hide yes)
			)
		)
		(property "MPN" "SI7613DN-T1-GE3"
			(at 228.6 78.74 90)
			(effects
				(font
					(size 1.27 1.27)
					(thickness 0.15)
				)
			)
		)
		(property "Manufacturer" "Vishay"
			(at 218.44 74.93 0)
			(effects
				(font
					(size 1.27 1.27)
					(thickness 0.15)
				)
				(justify left bottom)
				(hide yes)
			)
		)
		(property "Author" "Antmicro"
			(at 215.9 74.93 0)
			(effects
				(font
					(size 1.27 1.27)
					(thickness 0.15)
				)
				(justify left bottom)
				(hide yes)
			)
		)
		(property "License" "Apache-2.0"
			(at 213.36 74.93 0)
			(effects
				(font
					(size 1.27 1.27)
					(thickness 0.15)
				)
				(justify left bottom)
				(hide yes)
			)
		)
		(pin "4"
		)
		(pin "5"
		)
		(pin "3"
		)
		(pin "2"
		)
		(pin "1"
		)
		(instances
			(project "data-center-rdimm-ddr5-tester"
				(path ""
					(reference "Q27")
					(unit 1)
				)
			)
		)
	)
	(symbol
		(lib_id "antmicroResistors0402:R_47k_0402")
		(at 271.78 231.14 90)
		(unit 1)
		(exclude_from_sim no)
		(in_bom yes)
		(on_board yes)
		(dnp no)
		(fields_autoplaced yes)
		(property "Reference" "R25"
			(at 273.431 227.7694 90)
			(effects
				(font
					(size 1.27 1.27)
					(thickness 0.15)
				)
				(justify right)
			)
		)
		(property "Value" "R_47k_0402"
			(at 284.48 210.82 0)
			(effects
				(font
					(size 1.27 1.27)
					(thickness 0.15)
				)
				(justify left bottom)
				(hide yes)
			)
		)
		(property "Footprint" "antmicro-footprints:R_0402_1005Metric"
			(at 287.02 210.82 0)
			(effects
				(font
					(size 1.27 1.27)
					(thickness 0.15)
				)
				(justify left bottom)
				(hide yes)
			)
		)
		(property "Datasheet" "https://www.bourns.com/docs/product-datasheets/cr.pdf"
			(at 289.56 210.82 0)
			(effects
				(font
					(size 1.27 1.27)
					(thickness 0.15)
				)
				(justify left bottom)
				(hide yes)
			)
		)
		(property "Description" ""
			(at 271.78 231.14 0)
			(effects
				(font
					(size 1.27 1.27)
				)
				(hide yes)
			)
		)
		(property "MPN" "CR0402-FX-4702GLF"
			(at 292.1 210.82 0)
			(effects
				(font
					(size 1.27 1.27)
					(thickness 0.15)
				)
				(justify left bottom)
				(hide yes)
			)
		)
		(property "Manufacturer" "Bourns"
			(at 294.64 210.82 0)
			(effects
				(font
					(size 1.27 1.27)
					(thickness 0.15)
				)
				(justify left bottom)
				(hide yes)
			)
		)
		(property "License" "Apache-2.0"
			(at 297.18 210.82 0)
			(effects
				(font
					(size 1.27 1.27)
					(thickness 0.15)
				)
				(justify left bottom)
				(hide yes)
			)
		)
		(property "Author" "Antmicro"
			(at 299.72 210.82 0)
			(effects
				(font
					(size 1.27 1.27)
					(thickness 0.15)
				)
				(justify left bottom)
				(hide yes)
			)
		)
		(property "Val" "47k"
			(at 273.431 230.2931 90)
			(effects
				(font
					(size 1.27 1.27)
					(thickness 0.15)
				)
				(justify right)
			)
		)
		(property "Tolerance" "1%"
			(at 281.94 210.82 0)
			(effects
				(font
					(size 1.27 1.27)
				)
				(justify left bottom)
				(hide yes)
			)
		)
		(pin "1"
		)
		(pin "2"
		)
		(instances
			(project "data-center-rdimm-ddr5-tester"
				(path ""
					(reference "R25")
					(unit 1)
				)
			)
		)
	)
	(symbol
		(lib_id "antmicroCapacitors0603:C_10u_25V_0603")
		(at 281.94 115.57 90)
		(unit 1)
		(exclude_from_sim no)
		(in_bom yes)
		(on_board yes)
		(dnp no)
		(fields_autoplaced yes)
		(property "Reference" "C319"
			(at 284.48 111.7536 90)
			(effects
				(font
					(size 1.27 1.27)
					(thickness 0.15)
				)
				(justify right)
			)
		)
		(property "Value" "C_10u_25V_0603"
			(at 292.1 95.25 0)
			(effects
				(font
					(size 1.27 1.27)
					(thickness 0.15)
				)
				(justify left bottom)
				(hide yes)
			)
		)
		(property "Footprint" "antmicro-footprints:C_0603_1608Metric"
			(at 294.64 95.25 0)
			(effects
				(font
					(size 1.27 1.27)
					(thickness 0.15)
				)
				(justify left bottom)
				(hide yes)
			)
		)
		(property "Datasheet" "https://product.tdk.com/en/search/capacitor/ceramic/mlcc/info?part_no=C1608X5R1E106M080AC"
			(at 297.18 95.25 0)
			(effects
				(font
					(size 1.27 1.27)
					(thickness 0.15)
				)
				(justify left bottom)
				(hide yes)
			)
		)
		(property "Description" ""
			(at 281.94 115.57 0)
			(effects
				(font
					(size 1.27 1.27)
				)
				(hide yes)
			)
		)
		(property "MPN" "C1608X5R1E106M080AC"
			(at 299.72 95.25 0)
			(effects
				(font
					(size 1.27 1.27)
					(thickness 0.15)
				)
				(justify left bottom)
				(hide yes)
			)
		)
		(property "Manufacturer" "TDK"
			(at 302.26 95.25 0)
			(effects
				(font
					(size 1.27 1.27)
					(thickness 0.15)
				)
				(justify left bottom)
				(hide yes)
			)
		)
		(property "License" "Apache-2.0"
			(at 304.8 95.25 0)
			(effects
				(font
					(size 1.27 1.27)
					(thickness 0.15)
				)
				(justify left bottom)
				(hide yes)
			)
		)
		(property "Author" "Antmicro"
			(at 307.34 95.25 0)
			(effects
				(font
					(size 1.27 1.27)
					(thickness 0.15)
				)
				(justify left bottom)
				(hide yes)
			)
		)
		(property "Val" "10u"
			(at 284.48 114.2936 90)
			(effects
				(font
					(size 1.27 1.27)
					(thickness 0.15)
				)
				(justify right)
			)
		)
		(property "Voltage" "25V"
			(at 309.88 95.25 0)
			(effects
				(font
					(size 1.27 1.27)
				)
				(justify left bottom)
				(hide yes)
			)
		)
		(property "Dielectric" ""
			(at 312.42 95.25 0)
			(effects
				(font
					(size 1.27 1.27)
				)
				(justify left bottom)
				(hide yes)
			)
		)
		(pin "2"
		)
		(pin "1"
		)
		(instances
			(project "data-center-rdimm-ddr5-tester"
				(path ""
					(reference "C319")
					(unit 1)
				)
			)
		)
	)
	(symbol
		(lib_id "antmicroTransistorsFETsMOSFETsSingle:BSS138PW")
		(at 218.44 52.07 0)
		(unit 1)
		(exclude_from_sim no)
		(in_bom yes)
		(on_board yes)
		(dnp no)
		(property "Reference" "Q25"
			(at 229.87 48.26 0)
			(effects
				(font
					(size 1.27 1.27)
				)
				(justify left)
			)
		)
		(property "Value" "BSS138PW"
			(at 229.87 51.4349 0)
			(effects
				(font
					(size 1.27 1.27)
					(thickness 0.15)
				)
				(justify left)
			)
		)
		(property "Footprint" "antmicro-footprints:SC70-3"
			(at 241.3 63.5 0)
			(effects
				(font
					(size 1.27 1.27)
					(thickness 0.15)
				)
				(justify left bottom)
				(hide yes)
			)
		)
		(property "Datasheet" "https://assets.nexperia.com/documents/data-sheet/BSS138PW.pdf"
			(at 241.3 66.04 0)
			(effects
				(font
					(size 1.27 1.27)
					(thickness 0.15)
				)
				(justify left bottom)
				(hide yes)
			)
		)
		(property "Description" ""
			(at 218.44 52.07 0)
			(effects
				(font
					(size 1.27 1.27)
				)
				(hide yes)
			)
		)
		(property "MPN" "BSS138PW"
			(at 241.3 68.58 0)
			(effects
				(font
					(size 1.27 1.27)
					(thickness 0.15)
				)
				(justify left bottom)
				(hide yes)
			)
		)
		(property "Manufacturer" "Nexperia"
			(at 241.3 71.12 0)
			(effects
				(font
					(size 1.27 1.27)
					(thickness 0.15)
				)
				(justify left bottom)
				(hide yes)
			)
		)
		(property "Author" "Antmicro"
			(at 241.3 73.66 0)
			(effects
				(font
					(size 1.27 1.27)
					(thickness 0.15)
				)
				(justify left bottom)
				(hide yes)
			)
		)
		(property "License" "Apache-2.0"
			(at 241.3 76.2 0)
			(effects
				(font
					(size 1.27 1.27)
					(thickness 0.15)
				)
				(justify left bottom)
				(hide yes)
			)
		)
		(pin "1"
		)
		(pin "2"
		)
		(pin "3"
		)
		(instances
			(project "data-center-rdimm-ddr5-tester"
				(path ""
					(reference "Q25")
					(unit 1)
				)
			)
		)
	)
	(symbol
		(lib_id "antmicropower:GND")
		(at 271.78 245.11 0)
		(unit 1)
		(exclude_from_sim no)
		(in_bom yes)
		(on_board yes)
		(dnp no)
		(fields_autoplaced yes)
		(property "Reference" "#PWR034"
			(at 271.78 251.46 0)
			(effects
				(font
					(size 1.27 1.27)
				)
				(hide yes)
			)
		)
		(property "Value" "GND"
			(at 269.875 249.555 0)
			(effects
				(font
					(size 1.27 1.27)
					(thickness 0.15)
				)
				(justify left bottom)
			)
		)
		(property "Footprint" ""
			(at 280.67 252.73 0)
			(effects
				(font
					(size 1.27 1.27)
					(thickness 0.15)
				)
				(justify left bottom)
				(hide yes)
			)
		)
		(property "Datasheet" ""
			(at 280.67 257.81 0)
			(effects
				(font
					(size 1.27 1.27)
					(thickness 0.15)
				)
				(justify left bottom)
				(hide yes)
			)
		)
		(property "Description" ""
			(at 271.78 245.11 0)
			(effects
				(font
					(size 1.27 1.27)
				)
				(hide yes)
			)
		)
		(property "Author" "Antmicro"
			(at 280.67 250.19 0)
			(effects
				(font
					(size 1.27 1.27)
					(thickness 0.15)
				)
				(justify left bottom)
				(hide yes)
			)
		)
		(property "License" "Apache-2.0"
			(at 280.67 252.73 0)
			(effects
				(font
					(size 1.27 1.27)
					(thickness 0.15)
				)
				(justify left bottom)
				(hide yes)
			)
		)
		(pin "1"
		)
		(instances
			(project "data-center-rdimm-ddr5-tester"
				(path ""
					(reference "#PWR034")
					(unit 1)
				)
			)
		)
	)
	(symbol
		(lib_id "antmicroResistors0402:R_4k7_0402")
		(at 248.92 45.72 90)
		(unit 1)
		(exclude_from_sim no)
		(in_bom yes)
		(on_board yes)
		(dnp no)
		(fields_autoplaced yes)
		(property "Reference" "R242"
			(at 250.825 41.91 90)
			(effects
				(font
					(size 1.27 1.27)
					(thickness 0.15)
				)
				(justify right)
			)
		)
		(property "Value" "R_4k7_0402"
			(at 261.62 25.4 0)
			(effects
				(font
					(size 1.27 1.27)
					(thickness 0.15)
				)
				(justify left bottom)
				(hide yes)
			)
		)
		(property "Footprint" "antmicro-footprints:R_0402_1005Metric"
			(at 264.16 25.4 0)
			(effects
				(font
					(size 1.27 1.27)
					(thickness 0.15)
				)
				(justify left bottom)
				(hide yes)
			)
		)
		(property "Datasheet" "https://www.bourns.com/docs/product-datasheets/cr.pdf"
			(at 266.7 25.4 0)
			(effects
				(font
					(size 1.27 1.27)
					(thickness 0.15)
				)
				(justify left bottom)
				(hide yes)
			)
		)
		(property "Description" ""
			(at 248.92 45.72 0)
			(effects
				(font
					(size 1.27 1.27)
				)
				(hide yes)
			)
		)
		(property "MPN" "CR0402-FX-4701GLF"
			(at 269.24 25.4 0)
			(effects
				(font
					(size 1.27 1.27)
					(thickness 0.15)
				)
				(justify left bottom)
				(hide yes)
			)
		)
		(property "Manufacturer" "Bourns"
			(at 271.78 25.4 0)
			(effects
				(font
					(size 1.27 1.27)
					(thickness 0.15)
				)
				(justify left bottom)
				(hide yes)
			)
		)
		(property "License" "Apache-2.0"
			(at 274.32 25.4 0)
			(effects
				(font
					(size 1.27 1.27)
					(thickness 0.15)
				)
				(justify left bottom)
				(hide yes)
			)
		)
		(property "Author" "Antmicro"
			(at 276.86 25.4 0)
			(effects
				(font
					(size 1.27 1.27)
					(thickness 0.15)
				)
				(justify left bottom)
				(hide yes)
			)
		)
		(property "Val" "4k7"
			(at 250.825 44.45 90)
			(effects
				(font
					(size 1.27 1.27)
					(thickness 0.15)
				)
				(justify right)
			)
		)
		(property "Tolerance" "1%"
			(at 259.08 25.4 0)
			(effects
				(font
					(size 1.27 1.27)
				)
				(justify left bottom)
				(hide yes)
			)
		)
		(pin "2"
		)
		(pin "1"
		)
		(instances
			(project "data-center-rdimm-ddr5-tester"
				(path ""
					(reference "R242")
					(unit 1)
				)
			)
		)
	)
	(symbol
		(lib_id "antmicropower:GND")
		(at 347.98 204.47 0)
		(unit 1)
		(exclude_from_sim no)
		(in_bom yes)
		(on_board yes)
		(dnp no)
		(fields_autoplaced yes)
		(property "Reference" "#PWR0211"
			(at 347.98 210.82 0)
			(effects
				(font
					(size 1.27 1.27)
				)
				(hide yes)
			)
		)
		(property "Value" "GND"
			(at 346.075 208.915 0)
			(effects
				(font
					(size 1.27 1.27)
					(thickness 0.15)
				)
				(justify left bottom)
			)
		)
		(property "Footprint" ""
			(at 356.87 212.09 0)
			(effects
				(font
					(size 1.27 1.27)
					(thickness 0.15)
				)
				(justify left bottom)
				(hide yes)
			)
		)
		(property "Datasheet" ""
			(at 356.87 217.17 0)
			(effects
				(font
					(size 1.27 1.27)
					(thickness 0.15)
				)
				(justify left bottom)
				(hide yes)
			)
		)
		(property "Description" ""
			(at 347.98 204.47 0)
			(effects
				(font
					(size 1.27 1.27)
				)
				(hide yes)
			)
		)
		(property "Author" "Antmicro"
			(at 356.87 209.55 0)
			(effects
				(font
					(size 1.27 1.27)
					(thickness 0.15)
				)
				(justify left bottom)
				(hide yes)
			)
		)
		(property "License" "Apache-2.0"
			(at 356.87 212.09 0)
			(effects
				(font
					(size 1.27 1.27)
					(thickness 0.15)
				)
				(justify left bottom)
				(hide yes)
			)
		)
		(pin "1"
		)
		(instances
			(project "data-center-rdimm-ddr5-tester"
				(path ""
					(reference "#PWR0211")
					(unit 1)
				)
			)
		)
	)
	(symbol
		(lib_id "antmicropower:GND")
		(at 226.06 111.76 0)
		(unit 1)
		(exclude_from_sim no)
		(in_bom yes)
		(on_board yes)
		(dnp no)
		(fields_autoplaced yes)
		(property "Reference" "#PWR0539"
			(at 226.06 118.11 0)
			(effects
				(font
					(size 1.27 1.27)
				)
				(hide yes)
			)
		)
		(property "Value" "GND"
			(at 224.155 116.205 0)
			(effects
				(font
					(size 1.27 1.27)
					(thickness 0.15)
				)
				(justify left bottom)
			)
		)
		(property "Footprint" ""
			(at 234.95 119.38 0)
			(effects
				(font
					(size 1.27 1.27)
					(thickness 0.15)
				)
				(justify left bottom)
				(hide yes)
			)
		)
		(property "Datasheet" ""
			(at 234.95 124.46 0)
			(effects
				(font
					(size 1.27 1.27)
					(thickness 0.15)
				)
				(justify left bottom)
				(hide yes)
			)
		)
		(property "Description" ""
			(at 226.06 111.76 0)
			(effects
				(font
					(size 1.27 1.27)
				)
				(hide yes)
			)
		)
		(property "Author" "Antmicro"
			(at 234.95 116.84 0)
			(effects
				(font
					(size 1.27 1.27)
					(thickness 0.15)
				)
				(justify left bottom)
				(hide yes)
			)
		)
		(property "License" "Apache-2.0"
			(at 234.95 119.38 0)
			(effects
				(font
					(size 1.27 1.27)
					(thickness 0.15)
				)
				(justify left bottom)
				(hide yes)
			)
		)
		(pin "1"
		)
		(instances
			(project "data-center-rdimm-ddr5-tester"
				(path ""
					(reference "#PWR0539")
					(unit 1)
				)
			)
		)
	)
	(symbol
		(lib_id "antmicroCapacitors0402:C_100n_0402")
		(at 364.49 238.76 90)
		(unit 1)
		(exclude_from_sim no)
		(in_bom yes)
		(on_board yes)
		(dnp no)
		(fields_autoplaced yes)
		(property "Reference" "C9"
			(at 366.8141 235.383 90)
			(effects
				(font
					(size 1.27 1.27)
					(thickness 0.15)
				)
				(justify right)
			)
		)
		(property "Value" "C_100n_0402"
			(at 374.65 218.44 0)
			(effects
				(font
					(size 1.27 1.27)
					(thickness 0.15)
				)
				(justify left bottom)
				(hide yes)
			)
		)
		(property "Footprint" "antmicro-footprints:C_0402_1005Metric"
			(at 377.19 218.44 0)
			(effects
				(font
					(size 1.27 1.27)
					(thickness 0.15)
				)
				(justify left bottom)
				(hide yes)
			)
		)
		(property "Datasheet" "https://www.murata.com/products/productdetail?partno=GRM155R61H104KE14%23"
			(at 379.73 218.44 0)
			(effects
				(font
					(size 1.27 1.27)
					(thickness 0.15)
				)
				(justify left bottom)
				(hide yes)
			)
		)
		(property "Description" ""
			(at 364.49 238.76 0)
			(effects
				(font
					(size 1.27 1.27)
				)
				(hide yes)
			)
		)
		(property "MPN" "GRM155R61H104KE14D"
			(at 382.27 218.44 0)
			(effects
				(font
					(size 1.27 1.27)
					(thickness 0.15)
				)
				(justify left bottom)
				(hide yes)
			)
		)
		(property "Manufacturer" "Murata"
			(at 384.81 218.44 0)
			(effects
				(font
					(size 1.27 1.27)
					(thickness 0.15)
				)
				(justify left bottom)
				(hide yes)
			)
		)
		(property "License" "Apache-2.0"
			(at 387.35 218.44 0)
			(effects
				(font
					(size 1.27 1.27)
					(thickness 0.15)
				)
				(justify left bottom)
				(hide yes)
			)
		)
		(property "Author" "Antmicro"
			(at 389.89 218.44 0)
			(effects
				(font
					(size 1.27 1.27)
					(thickness 0.15)
				)
				(justify left bottom)
				(hide yes)
			)
		)
		(property "Val" "100n"
			(at 366.8141 237.9067 90)
			(effects
				(font
					(size 1.27 1.27)
					(thickness 0.15)
				)
				(justify right)
			)
		)
		(property "Voltage" "50V"
			(at 392.43 218.44 0)
			(effects
				(font
					(size 1.27 1.27)
				)
				(justify left bottom)
				(hide yes)
			)
		)
		(property "Dielectric" "X5R"
			(at 394.97 218.44 0)
			(effects
				(font
					(size 1.27 1.27)
				)
				(justify left bottom)
				(hide yes)
			)
		)
		(pin "1"
		)
		(pin "2"
		)
		(instances
			(project "data-center-rdimm-ddr5-tester"
				(path ""
					(reference "C9")
					(unit 1)
				)
			)
		)
	)
	(symbol
		(lib_id "antmicropower:GND")
		(at 356.87 100.33 0)
		(mirror y)
		(unit 1)
		(exclude_from_sim no)
		(in_bom yes)
		(on_board yes)
		(dnp no)
		(fields_autoplaced yes)
		(property "Reference" "#PWR039"
			(at 356.87 106.68 0)
			(effects
				(font
					(size 1.27 1.27)
				)
				(hide yes)
			)
		)
		(property "Value" "GND"
			(at 358.775 104.775 0)
			(effects
				(font
					(size 1.27 1.27)
					(thickness 0.15)
				)
				(justify left bottom)
			)
		)
		(property "Footprint" ""
			(at 347.98 107.95 0)
			(effects
				(font
					(size 1.27 1.27)
					(thickness 0.15)
				)
				(justify left bottom)
				(hide yes)
			)
		)
		(property "Datasheet" ""
			(at 347.98 113.03 0)
			(effects
				(font
					(size 1.27 1.27)
					(thickness 0.15)
				)
				(justify left bottom)
				(hide yes)
			)
		)
		(property "Description" ""
			(at 356.87 100.33 0)
			(effects
				(font
					(size 1.27 1.27)
				)
				(hide yes)
			)
		)
		(property "Author" "Antmicro"
			(at 347.98 105.41 0)
			(effects
				(font
					(size 1.27 1.27)
					(thickness 0.15)
				)
				(justify left bottom)
				(hide yes)
			)
		)
		(property "License" "Apache-2.0"
			(at 347.98 107.95 0)
			(effects
				(font
					(size 1.27 1.27)
					(thickness 0.15)
				)
				(justify left bottom)
				(hide yes)
			)
		)
		(pin "1"
		)
		(instances
			(project "data-center-rdimm-ddr5-tester"
				(path ""
					(reference "#PWR039")
					(unit 1)
				)
			)
		)
	)
	(symbol
		(lib_id "antmicroResistors0402:R_0R_0402")
		(at 271.78 243.84 90)
		(unit 1)
		(exclude_from_sim no)
		(in_bom no)
		(on_board yes)
		(dnp yes)
		(property "Reference" "R26"
			(at 273.431 239.2035 90)
			(effects
				(font
					(size 1.27 1.27)
					(thickness 0.15)
				)
				(justify right)
				(hide yes)
			)
		)
		(property "Value" "R_0R_0402"
			(at 284.48 223.52 0)
			(effects
				(font
					(size 1.27 1.27)
					(thickness 0.15)
				)
				(justify left bottom)
				(hide yes)
			)
		)
		(property "Footprint" "antmicro-footprints:R_0402_1005Metric"
			(at 287.02 223.52 0)
			(effects
				(font
					(size 1.27 1.27)
					(thickness 0.15)
				)
				(justify left bottom)
				(hide yes)
			)
		)
		(property "Datasheet" "https://industrial.panasonic.com/cdbs/www-data/pdf/RDA0000/AOA0000C301.pdf"
			(at 289.56 223.52 0)
			(effects
				(font
					(size 1.27 1.27)
					(thickness 0.15)
				)
				(justify left bottom)
				(hide yes)
			)
		)
		(property "Description" ""
			(at 271.78 243.84 0)
			(effects
				(font
					(size 1.27 1.27)
				)
				(hide yes)
			)
		)
		(property "MPN" "ERJ2GE0R00X"
			(at 292.1 223.52 0)
			(effects
				(font
					(size 1.27 1.27)
					(thickness 0.15)
				)
				(justify left bottom)
				(hide yes)
			)
		)
		(property "Manufacturer" "Panasonic"
			(at 294.64 223.52 0)
			(effects
				(font
					(size 1.27 1.27)
					(thickness 0.15)
				)
				(justify left bottom)
				(hide yes)
			)
		)
		(property "License" "Apache-2.0"
			(at 297.18 223.52 0)
			(effects
				(font
					(size 1.27 1.27)
					(thickness 0.15)
				)
				(justify left bottom)
				(hide yes)
			)
		)
		(property "Author" "Antmicro"
			(at 299.72 223.52 0)
			(effects
				(font
					(size 1.27 1.27)
					(thickness 0.15)
				)
				(justify left bottom)
				(hide yes)
			)
		)
		(property "Val" "0R"
			(at 273.431 241.7272 90)
			(effects
				(font
					(size 1.27 1.27)
					(thickness 0.15)
				)
				(justify right)
			)
		)
		(property "Tolerance" "~"
			(at 281.94 223.52 0)
			(effects
				(font
					(size 1.27 1.27)
				)
				(justify left bottom)
				(hide yes)
			)
		)
		(property "Current" "1A"
			(at 302.26 223.52 0)
			(effects
				(font
					(size 1.27 1.27)
					(thickness 0.15)
				)
				(justify left bottom)
				(hide yes)
			)
		)
		(pin "1"
		)
		(pin "2"
		)
		(instances
			(project "data-center-rdimm-ddr5-tester"
				(path ""
					(reference "R26")
					(unit 1)
				)
			)
		)
	)
	(symbol
		(lib_id "antmicroResistors0402:R_47k_0402")
		(at 215.9 59.69 90)
		(unit 1)
		(exclude_from_sim no)
		(in_bom yes)
		(on_board yes)
		(dnp no)
		(fields_autoplaced yes)
		(property "Reference" "R240"
			(at 218.44 55.88 90)
			(effects
				(font
					(size 1.27 1.27)
					(thickness 0.15)
				)
				(justify right)
			)
		)
		(property "Value" "R_47k_0402"
			(at 228.6 39.37 0)
			(effects
				(font
					(size 1.27 1.27)
					(thickness 0.15)
				)
				(justify left bottom)
				(hide yes)
			)
		)
		(property "Footprint" "antmicro-footprints:R_0402_1005Metric"
			(at 231.14 39.37 0)
			(effects
				(font
					(size 1.27 1.27)
					(thickness 0.15)
				)
				(justify left bottom)
				(hide yes)
			)
		)
		(property "Datasheet" "https://www.bourns.com/docs/product-datasheets/cr.pdf"
			(at 233.68 39.37 0)
			(effects
				(font
					(size 1.27 1.27)
					(thickness 0.15)
				)
				(justify left bottom)
				(hide yes)
			)
		)
		(property "Description" ""
			(at 215.9 59.69 0)
			(effects
				(font
					(size 1.27 1.27)
				)
				(hide yes)
			)
		)
		(property "MPN" "CR0402-FX-4702GLF"
			(at 236.22 39.37 0)
			(effects
				(font
					(size 1.27 1.27)
					(thickness 0.15)
				)
				(justify left bottom)
				(hide yes)
			)
		)
		(property "Manufacturer" "Bourns"
			(at 238.76 39.37 0)
			(effects
				(font
					(size 1.27 1.27)
					(thickness 0.15)
				)
				(justify left bottom)
				(hide yes)
			)
		)
		(property "License" "Apache-2.0"
			(at 241.3 39.37 0)
			(effects
				(font
					(size 1.27 1.27)
					(thickness 0.15)
				)
				(justify left bottom)
				(hide yes)
			)
		)
		(property "Author" "Antmicro"
			(at 243.84 39.37 0)
			(effects
				(font
					(size 1.27 1.27)
					(thickness 0.15)
				)
				(justify left bottom)
				(hide yes)
			)
		)
		(property "Val" "47k"
			(at 218.44 58.42 90)
			(effects
				(font
					(size 1.27 1.27)
					(thickness 0.15)
				)
				(justify right)
			)
		)
		(property "Tolerance" "1%"
			(at 226.06 39.37 0)
			(effects
				(font
					(size 1.27 1.27)
				)
				(justify left bottom)
				(hide yes)
			)
		)
		(pin "2"
		)
		(pin "1"
		)
		(instances
			(project "data-center-rdimm-ddr5-tester"
				(path ""
					(reference "R240")
					(unit 1)
				)
			)
		)
	)
	(symbol
		(lib_id "antmicroTransistorsFETsMOSFETsSingle:BSS138PW")
		(at 218.44 102.87 0)
		(unit 1)
		(exclude_from_sim no)
		(in_bom yes)
		(on_board yes)
		(dnp no)
		(property "Reference" "Q26"
			(at 229.87 99.06 0)
			(effects
				(font
					(size 1.27 1.27)
				)
				(justify left)
			)
		)
		(property "Value" "BSS138PW"
			(at 229.87 102.2349 0)
			(effects
				(font
					(size 1.27 1.27)
					(thickness 0.15)
				)
				(justify left)
			)
		)
		(property "Footprint" "antmicro-footprints:SC70-3"
			(at 241.3 114.3 0)
			(effects
				(font
					(size 1.27 1.27)
					(thickness 0.15)
				)
				(justify left bottom)
				(hide yes)
			)
		)
		(property "Datasheet" "https://assets.nexperia.com/documents/data-sheet/BSS138PW.pdf"
			(at 241.3 116.84 0)
			(effects
				(font
					(size 1.27 1.27)
					(thickness 0.15)
				)
				(justify left bottom)
				(hide yes)
			)
		)
		(property "Description" ""
			(at 218.44 102.87 0)
			(effects
				(font
					(size 1.27 1.27)
				)
				(hide yes)
			)
		)
		(property "MPN" "BSS138PW"
			(at 241.3 119.38 0)
			(effects
				(font
					(size 1.27 1.27)
					(thickness 0.15)
				)
				(justify left bottom)
				(hide yes)
			)
		)
		(property "Manufacturer" "Nexperia"
			(at 241.3 121.92 0)
			(effects
				(font
					(size 1.27 1.27)
					(thickness 0.15)
				)
				(justify left bottom)
				(hide yes)
			)
		)
		(property "Author" "Antmicro"
			(at 241.3 124.46 0)
			(effects
				(font
					(size 1.27 1.27)
					(thickness 0.15)
				)
				(justify left bottom)
				(hide yes)
			)
		)
		(property "License" "Apache-2.0"
			(at 241.3 127 0)
			(effects
				(font
					(size 1.27 1.27)
					(thickness 0.15)
				)
				(justify left bottom)
				(hide yes)
			)
		)
		(pin "1"
		)
		(pin "2"
		)
		(pin "3"
		)
		(instances
			(project "data-center-rdimm-ddr5-tester"
				(path ""
					(reference "Q26")
					(unit 1)
				)
			)
		)
	)
	(symbol
		(lib_id "antmicropower:+3V3")
		(at 271.78 223.52 0)
		(unit 1)
		(exclude_from_sim no)
		(in_bom yes)
		(on_board yes)
		(dnp no)
		(fields_autoplaced yes)
		(property "Reference" "#PWR032"
			(at 287.02 226.06 0)
			(effects
				(font
					(size 1.27 1.27)
					(thickness 0.15)
				)
				(justify left bottom)
				(hide yes)
			)
		)
		(property "Value" "+3V3"
			(at 268.605 220.98 0)
			(effects
				(font
					(size 1.27 1.27)
					(thickness 0.15)
				)
				(justify left bottom)
			)
		)
		(property "Footprint" ""
			(at 287.02 231.14 0)
			(effects
				(font
					(size 1.27 1.27)
					(thickness 0.15)
				)
				(justify left bottom)
				(hide yes)
			)
		)
		(property "Datasheet" ""
			(at 287.02 233.68 0)
			(effects
				(font
					(size 1.27 1.27)
					(thickness 0.15)
				)
				(justify left bottom)
				(hide yes)
			)
		)
		(property "Description" ""
			(at 271.78 223.52 0)
			(effects
				(font
					(size 1.27 1.27)
				)
				(hide yes)
			)
		)
		(property "Author" "Antmicro"
			(at 287.02 226.06 0)
			(effects
				(font
					(size 1.27 1.27)
					(thickness 0.15)
				)
				(justify left bottom)
				(hide yes)
			)
		)
		(property "License" "Apache-2.0"
			(at 287.02 228.6 0)
			(effects
				(font
					(size 1.27 1.27)
					(thickness 0.15)
				)
				(justify left bottom)
				(hide yes)
			)
		)
		(pin "1"
		)
		(instances
			(project "data-center-rdimm-ddr5-tester"
				(path ""
					(reference "#PWR032")
					(unit 1)
				)
			)
		)
	)
	(symbol
		(lib_id "antmicropower:VDD")
		(at 374.65 232.41 0)
		(unit 1)
		(exclude_from_sim no)
		(in_bom yes)
		(on_board yes)
		(dnp no)
		(fields_autoplaced yes)
		(property "Reference" "#PWR0117"
			(at 374.65 236.22 0)
			(effects
				(font
					(size 1.27 1.27)
				)
				(hide yes)
			)
		)
		(property "Value" "VDDQ"
			(at 374.65 227.33 0)
			(effects
				(font
					(size 1.27 1.27)
				)
			)
		)
		(property "Footprint" ""
			(at 374.65 232.41 0)
			(effects
				(font
					(size 1.27 1.27)
				)
				(hide yes)
			)
		)
		(property "Datasheet" ""
			(at 374.65 232.41 0)
			(effects
				(font
					(size 1.27 1.27)
				)
				(hide yes)
			)
		)
		(property "Description" ""
			(at 374.65 232.41 0)
			(effects
				(font
					(size 1.27 1.27)
				)
				(hide yes)
			)
		)
		(pin "1"
		)
		(instances
			(project "data-center-rdimm-ddr5-tester"
				(path ""
					(reference "#PWR0117")
					(unit 1)
				)
			)
		)
	)
	(symbol
		(lib_id "antmicroResistors0402:R_330R_0402")
		(at 270.51 161.29 270)
		(unit 1)
		(exclude_from_sim no)
		(in_bom yes)
		(on_board yes)
		(dnp no)
		(fields_autoplaced yes)
		(property "Reference" "R62"
			(at 273.05 162.56 90)
			(effects
				(font
					(size 1.27 1.27)
				)
				(justify left)
			)
		)
		(property "Value" "R_330R_0402"
			(at 257.81 181.61 0)
			(effects
				(font
					(size 1.27 1.27)
					(thickness 0.15)
				)
				(justify left bottom)
				(hide yes)
			)
		)
		(property "Footprint" "antmicro-footprints:R_0402_1005Metric"
			(at 255.27 181.61 0)
			(effects
				(font
					(size 1.27 1.27)
					(thickness 0.15)
				)
				(justify left bottom)
				(hide yes)
			)
		)
		(property "Datasheet" "https://www.bourns.com/docs/product-datasheets/cr.pdf"
			(at 252.73 181.61 0)
			(effects
				(font
					(size 1.27 1.27)
					(thickness 0.15)
				)
				(justify left bottom)
				(hide yes)
			)
		)
		(property "Description" ""
			(at 270.51 161.29 0)
			(effects
				(font
					(size 1.27 1.27)
				)
				(hide yes)
			)
		)
		(property "Manufacturer" "Bourns"
			(at 247.65 181.61 0)
			(effects
				(font
					(size 1.27 1.27)
					(thickness 0.15)
				)
				(justify left bottom)
				(hide yes)
			)
		)
		(property "MPN" "CR0402-FX-3300GLF"
			(at 250.19 181.61 0)
			(effects
				(font
					(size 1.27 1.27)
					(thickness 0.15)
				)
				(justify left bottom)
				(hide yes)
			)
		)
		(property "Val" "330R"
			(at 273.05 165.7349 90)
			(effects
				(font
					(size 1.27 1.27)
					(thickness 0.15)
				)
				(justify left)
			)
		)
		(property "License" "Apache-2.0"
			(at 245.11 181.61 0)
			(effects
				(font
					(size 1.27 1.27)
					(thickness 0.15)
				)
				(justify left bottom)
				(hide yes)
			)
		)
		(property "Author" "Antmicro"
			(at 242.57 181.61 0)
			(effects
				(font
					(size 1.27 1.27)
					(thickness 0.15)
				)
				(justify left bottom)
				(hide yes)
			)
		)
		(property "Tolerance" "1%"
			(at 260.35 181.61 0)
			(effects
				(font
					(size 1.27 1.27)
				)
				(justify left bottom)
				(hide yes)
			)
		)
		(pin "1"
		)
		(pin "2"
		)
		(instances
			(project "data-center-rdimm-ddr5-tester"
				(path ""
					(reference "R62")
					(unit 1)
				)
			)
		)
	)
	(symbol
		(lib_id "antmicroResistors0402:R_47k_0402")
		(at 215.9 40.64 90)
		(unit 1)
		(exclude_from_sim no)
		(in_bom yes)
		(on_board yes)
		(dnp no)
		(fields_autoplaced yes)
		(property "Reference" "R238"
			(at 218.44 36.83 90)
			(effects
				(font
					(size 1.27 1.27)
					(thickness 0.15)
				)
				(justify right)
			)
		)
		(property "Value" "R_47k_0402"
			(at 228.6 20.32 0)
			(effects
				(font
					(size 1.27 1.27)
					(thickness 0.15)
				)
				(justify left bottom)
				(hide yes)
			)
		)
		(property "Footprint" "antmicro-footprints:R_0402_1005Metric"
			(at 231.14 20.32 0)
			(effects
				(font
					(size 1.27 1.27)
					(thickness 0.15)
				)
				(justify left bottom)
				(hide yes)
			)
		)
		(property "Datasheet" "https://www.bourns.com/docs/product-datasheets/cr.pdf"
			(at 233.68 20.32 0)
			(effects
				(font
					(size 1.27 1.27)
					(thickness 0.15)
				)
				(justify left bottom)
				(hide yes)
			)
		)
		(property "Description" ""
			(at 215.9 40.64 0)
			(effects
				(font
					(size 1.27 1.27)
				)
				(hide yes)
			)
		)
		(property "MPN" "CR0402-FX-4702GLF"
			(at 236.22 20.32 0)
			(effects
				(font
					(size 1.27 1.27)
					(thickness 0.15)
				)
				(justify left bottom)
				(hide yes)
			)
		)
		(property "Manufacturer" "Bourns"
			(at 238.76 20.32 0)
			(effects
				(font
					(size 1.27 1.27)
					(thickness 0.15)
				)
				(justify left bottom)
				(hide yes)
			)
		)
		(property "License" "Apache-2.0"
			(at 241.3 20.32 0)
			(effects
				(font
					(size 1.27 1.27)
					(thickness 0.15)
				)
				(justify left bottom)
				(hide yes)
			)
		)
		(property "Author" "Antmicro"
			(at 243.84 20.32 0)
			(effects
				(font
					(size 1.27 1.27)
					(thickness 0.15)
				)
				(justify left bottom)
				(hide yes)
			)
		)
		(property "Val" "47k"
			(at 218.44 39.37 90)
			(effects
				(font
					(size 1.27 1.27)
					(thickness 0.15)
				)
				(justify right)
			)
		)
		(property "Tolerance" "1%"
			(at 226.06 20.32 0)
			(effects
				(font
					(size 1.27 1.27)
				)
				(justify left bottom)
				(hide yes)
			)
		)
		(pin "2"
		)
		(pin "1"
		)
		(instances
			(project "data-center-rdimm-ddr5-tester"
				(path ""
					(reference "R238")
					(unit 1)
				)
			)
		)
	)
	(symbol
		(lib_id "antmicroResistors0402:R_330R_0402")
		(at 251.46 161.29 270)
		(unit 1)
		(exclude_from_sim no)
		(in_bom yes)
		(on_board yes)
		(dnp no)
		(fields_autoplaced yes)
		(property "Reference" "R61"
			(at 254 162.56 90)
			(effects
				(font
					(size 1.27 1.27)
				)
				(justify left)
			)
		)
		(property "Value" "R_330R_0402"
			(at 238.76 181.61 0)
			(effects
				(font
					(size 1.27 1.27)
					(thickness 0.15)
				)
				(justify left bottom)
				(hide yes)
			)
		)
		(property "Footprint" "antmicro-footprints:R_0402_1005Metric"
			(at 236.22 181.61 0)
			(effects
				(font
					(size 1.27 1.27)
					(thickness 0.15)
				)
				(justify left bottom)
				(hide yes)
			)
		)
		(property "Datasheet" "https://www.bourns.com/docs/product-datasheets/cr.pdf"
			(at 233.68 181.61 0)
			(effects
				(font
					(size 1.27 1.27)
					(thickness 0.15)
				)
				(justify left bottom)
				(hide yes)
			)
		)
		(property "Description" ""
			(at 251.46 161.29 0)
			(effects
				(font
					(size 1.27 1.27)
				)
				(hide yes)
			)
		)
		(property "Manufacturer" "Bourns"
			(at 228.6 181.61 0)
			(effects
				(font
					(size 1.27 1.27)
					(thickness 0.15)
				)
				(justify left bottom)
				(hide yes)
			)
		)
		(property "MPN" "CR0402-FX-3300GLF"
			(at 231.14 181.61 0)
			(effects
				(font
					(size 1.27 1.27)
					(thickness 0.15)
				)
				(justify left bottom)
				(hide yes)
			)
		)
		(property "Val" "330R"
			(at 254 165.7349 90)
			(effects
				(font
					(size 1.27 1.27)
					(thickness 0.15)
				)
				(justify left)
			)
		)
		(property "License" "Apache-2.0"
			(at 226.06 181.61 0)
			(effects
				(font
					(size 1.27 1.27)
					(thickness 0.15)
				)
				(justify left bottom)
				(hide yes)
			)
		)
		(property "Author" "Antmicro"
			(at 223.52 181.61 0)
			(effects
				(font
					(size 1.27 1.27)
					(thickness 0.15)
				)
				(justify left bottom)
				(hide yes)
			)
		)
		(property "Tolerance" "1%"
			(at 241.3 181.61 0)
			(effects
				(font
					(size 1.27 1.27)
				)
				(justify left bottom)
				(hide yes)
			)
		)
		(pin "1"
		)
		(pin "2"
		)
		(instances
			(project "data-center-rdimm-ddr5-tester"
				(path ""
					(reference "R61")
					(unit 1)
				)
			)
		)
	)
	(symbol
		(lib_id "antmicropower:GND")
		(at 251.46 204.47 0)
		(unit 1)
		(exclude_from_sim no)
		(in_bom yes)
		(on_board yes)
		(dnp no)
		(fields_autoplaced yes)
		(property "Reference" "#PWR0201"
			(at 251.46 210.82 0)
			(effects
				(font
					(size 1.27 1.27)
				)
				(hide yes)
			)
		)
		(property "Value" "GND"
			(at 249.555 208.915 0)
			(effects
				(font
					(size 1.27 1.27)
					(thickness 0.15)
				)
				(justify left bottom)
			)
		)
		(property "Footprint" ""
			(at 260.35 212.09 0)
			(effects
				(font
					(size 1.27 1.27)
					(thickness 0.15)
				)
				(justify left bottom)
				(hide yes)
			)
		)
		(property "Datasheet" ""
			(at 260.35 217.17 0)
			(effects
				(font
					(size 1.27 1.27)
					(thickness 0.15)
				)
				(justify left bottom)
				(hide yes)
			)
		)
		(property "Description" ""
			(at 251.46 204.47 0)
			(effects
				(font
					(size 1.27 1.27)
				)
				(hide yes)
			)
		)
		(property "Author" "Antmicro"
			(at 260.35 209.55 0)
			(effects
				(font
					(size 1.27 1.27)
					(thickness 0.15)
				)
				(justify left bottom)
				(hide yes)
			)
		)
		(property "License" "Apache-2.0"
			(at 260.35 212.09 0)
			(effects
				(font
					(size 1.27 1.27)
					(thickness 0.15)
				)
				(justify left bottom)
				(hide yes)
			)
		)
		(pin "1"
		)
		(instances
			(project "data-center-rdimm-ddr5-tester"
				(path ""
					(reference "#PWR0201")
					(unit 1)
				)
			)
		)
	)
	(symbol
		(lib_id "antmicropower:GND")
		(at 322.58 100.33 0)
		(unit 1)
		(exclude_from_sim no)
		(in_bom yes)
		(on_board yes)
		(dnp no)
		(fields_autoplaced yes)
		(property "Reference" "#PWR038"
			(at 322.58 106.68 0)
			(effects
				(font
					(size 1.27 1.27)
				)
				(hide yes)
			)
		)
		(property "Value" "GND"
			(at 320.675 104.775 0)
			(effects
				(font
					(size 1.27 1.27)
					(thickness 0.15)
				)
				(justify left bottom)
			)
		)
		(property "Footprint" ""
			(at 331.47 107.95 0)
			(effects
				(font
					(size 1.27 1.27)
					(thickness 0.15)
				)
				(justify left bottom)
				(hide yes)
			)
		)
		(property "Datasheet" ""
			(at 331.47 113.03 0)
			(effects
				(font
					(size 1.27 1.27)
					(thickness 0.15)
				)
				(justify left bottom)
				(hide yes)
			)
		)
		(property "Description" ""
			(at 322.58 100.33 0)
			(effects
				(font
					(size 1.27 1.27)
				)
				(hide yes)
			)
		)
		(property "Author" "Antmicro"
			(at 331.47 105.41 0)
			(effects
				(font
					(size 1.27 1.27)
					(thickness 0.15)
				)
				(justify left bottom)
				(hide yes)
			)
		)
		(property "License" "Apache-2.0"
			(at 331.47 107.95 0)
			(effects
				(font
					(size 1.27 1.27)
					(thickness 0.15)
				)
				(justify left bottom)
				(hide yes)
			)
		)
		(pin "1"
		)
		(instances
			(project "data-center-rdimm-ddr5-tester"
				(path ""
					(reference "#PWR038")
					(unit 1)
				)
			)
		)
	)
	(symbol
		(lib_id "antmicropower:GND")
		(at 271.78 116.84 0)
		(unit 1)
		(exclude_from_sim no)
		(in_bom yes)
		(on_board yes)
		(dnp no)
		(fields_autoplaced yes)
		(property "Reference" "#PWR035"
			(at 271.78 123.19 0)
			(effects
				(font
					(size 1.27 1.27)
				)
				(hide yes)
			)
		)
		(property "Value" "GND"
			(at 269.875 121.285 0)
			(effects
				(font
					(size 1.27 1.27)
					(thickness 0.15)
				)
				(justify left bottom)
			)
		)
		(property "Footprint" ""
			(at 280.67 124.46 0)
			(effects
				(font
					(size 1.27 1.27)
					(thickness 0.15)
				)
				(justify left bottom)
				(hide yes)
			)
		)
		(property "Datasheet" ""
			(at 280.67 129.54 0)
			(effects
				(font
					(size 1.27 1.27)
					(thickness 0.15)
				)
				(justify left bottom)
				(hide yes)
			)
		)
		(property "Description" ""
			(at 271.78 116.84 0)
			(effects
				(font
					(size 1.27 1.27)
				)
				(hide yes)
			)
		)
		(property "Author" "Antmicro"
			(at 280.67 121.92 0)
			(effects
				(font
					(size 1.27 1.27)
					(thickness 0.15)
				)
				(justify left bottom)
				(hide yes)
			)
		)
		(property "License" "Apache-2.0"
			(at 280.67 124.46 0)
			(effects
				(font
					(size 1.27 1.27)
					(thickness 0.15)
				)
				(justify left bottom)
				(hide yes)
			)
		)
		(pin "1"
		)
		(instances
			(project "data-center-rdimm-ddr5-tester"
				(path ""
					(reference "#PWR035")
					(unit 1)
				)
			)
		)
	)
	(symbol
		(lib_id "antmicroResistors0402:R_330R_0402")
		(at 248.92 96.52 90)
		(unit 1)
		(exclude_from_sim no)
		(in_bom yes)
		(on_board yes)
		(dnp no)
		(fields_autoplaced yes)
		(property "Reference" "R246"
			(at 251.46 92.71 90)
			(effects
				(font
					(size 1.27 1.27)
					(thickness 0.15)
				)
				(justify right)
			)
		)
		(property "Value" "R_330R_0402"
			(at 261.62 76.2 0)
			(effects
				(font
					(size 1.27 1.27)
					(thickness 0.15)
				)
				(justify left bottom)
				(hide yes)
			)
		)
		(property "Footprint" "antmicro-footprints:R_0402_1005Metric"
			(at 264.16 76.2 0)
			(effects
				(font
					(size 1.27 1.27)
					(thickness 0.15)
				)
				(justify left bottom)
				(hide yes)
			)
		)
		(property "Datasheet" "https://www.bourns.com/docs/product-datasheets/cr.pdf"
			(at 266.7 76.2 0)
			(effects
				(font
					(size 1.27 1.27)
					(thickness 0.15)
				)
				(justify left bottom)
				(hide yes)
			)
		)
		(property "Description" ""
			(at 248.92 96.52 0)
			(effects
				(font
					(size 1.27 1.27)
				)
				(hide yes)
			)
		)
		(property "MPN" "CR0402-FX-3300GLF"
			(at 269.24 76.2 0)
			(effects
				(font
					(size 1.27 1.27)
					(thickness 0.15)
				)
				(justify left bottom)
				(hide yes)
			)
		)
		(property "Manufacturer" "Bourns"
			(at 271.78 76.2 0)
			(effects
				(font
					(size 1.27 1.27)
					(thickness 0.15)
				)
				(justify left bottom)
				(hide yes)
			)
		)
		(property "License" "Apache-2.0"
			(at 274.32 76.2 0)
			(effects
				(font
					(size 1.27 1.27)
					(thickness 0.15)
				)
				(justify left bottom)
				(hide yes)
			)
		)
		(property "Author" "Antmicro"
			(at 276.86 76.2 0)
			(effects
				(font
					(size 1.27 1.27)
					(thickness 0.15)
				)
				(justify left bottom)
				(hide yes)
			)
		)
		(property "Val" "330R"
			(at 251.46 95.25 90)
			(effects
				(font
					(size 1.27 1.27)
					(thickness 0.15)
				)
				(justify right)
			)
		)
		(property "Tolerance" "1%"
			(at 259.08 76.2 0)
			(effects
				(font
					(size 1.27 1.27)
				)
				(justify left bottom)
				(hide yes)
			)
		)
		(pin "1"
		)
		(pin "2"
		)
		(instances
			(project "data-center-rdimm-ddr5-tester"
				(path ""
					(reference "R246")
					(unit 1)
				)
			)
		)
	)
	(symbol
		(lib_id "antmicroTransistorsFETsMOSFETsSingle:BSS138PW")
		(at 262.89 186.69 0)
		(unit 1)
		(exclude_from_sim no)
		(in_bom yes)
		(on_board yes)
		(dnp no)
		(fields_autoplaced yes)
		(property "Reference" "Q10"
			(at 274.32 182.88 0)
			(effects
				(font
					(size 1.27 1.27)
				)
				(justify left)
			)
		)
		(property "Value" "BSS138PW"
			(at 274.32 186.0549 0)
			(effects
				(font
					(size 1.27 1.27)
					(thickness 0.15)
				)
				(justify left)
			)
		)
		(property "Footprint" "antmicro-footprints:SC70-3"
			(at 285.75 198.12 0)
			(effects
				(font
					(size 1.27 1.27)
					(thickness 0.15)
				)
				(justify left bottom)
				(hide yes)
			)
		)
		(property "Datasheet" "https://assets.nexperia.com/documents/data-sheet/BSS138PW.pdf"
			(at 285.75 200.66 0)
			(effects
				(font
					(size 1.27 1.27)
					(thickness 0.15)
				)
				(justify left bottom)
				(hide yes)
			)
		)
		(property "Description" ""
			(at 262.89 186.69 0)
			(effects
				(font
					(size 1.27 1.27)
				)
				(hide yes)
			)
		)
		(property "MPN" "BSS138PW"
			(at 285.75 203.2 0)
			(effects
				(font
					(size 1.27 1.27)
					(thickness 0.15)
				)
				(justify left bottom)
				(hide yes)
			)
		)
		(property "Manufacturer" "Nexperia"
			(at 285.75 205.74 0)
			(effects
				(font
					(size 1.27 1.27)
					(thickness 0.15)
				)
				(justify left bottom)
				(hide yes)
			)
		)
		(property "Author" "Antmicro"
			(at 285.75 208.28 0)
			(effects
				(font
					(size 1.27 1.27)
					(thickness 0.15)
				)
				(justify left bottom)
				(hide yes)
			)
		)
		(property "License" "Apache-2.0"
			(at 285.75 210.82 0)
			(effects
				(font
					(size 1.27 1.27)
					(thickness 0.15)
				)
				(justify left bottom)
				(hide yes)
			)
		)
		(pin "1"
		)
		(pin "2"
		)
		(pin "3"
		)
		(instances
			(project "data-center-rdimm-ddr5-tester"
				(path ""
					(reference "Q10")
					(unit 1)
				)
			)
		)
	)
	(symbol
		(lib_id "antmicropower:GND")
		(at 270.51 204.47 0)
		(unit 1)
		(exclude_from_sim no)
		(in_bom yes)
		(on_board yes)
		(dnp no)
		(fields_autoplaced yes)
		(property "Reference" "#PWR0203"
			(at 270.51 210.82 0)
			(effects
				(font
					(size 1.27 1.27)
				)
				(hide yes)
			)
		)
		(property "Value" "GND"
			(at 268.605 208.915 0)
			(effects
				(font
					(size 1.27 1.27)
					(thickness 0.15)
				)
				(justify left bottom)
			)
		)
		(property "Footprint" ""
			(at 279.4 212.09 0)
			(effects
				(font
					(size 1.27 1.27)
					(thickness 0.15)
				)
				(justify left bottom)
				(hide yes)
			)
		)
		(property "Datasheet" ""
			(at 279.4 217.17 0)
			(effects
				(font
					(size 1.27 1.27)
					(thickness 0.15)
				)
				(justify left bottom)
				(hide yes)
			)
		)
		(property "Description" ""
			(at 270.51 204.47 0)
			(effects
				(font
					(size 1.27 1.27)
				)
				(hide yes)
			)
		)
		(property "Author" "Antmicro"
			(at 279.4 209.55 0)
			(effects
				(font
					(size 1.27 1.27)
					(thickness 0.15)
				)
				(justify left bottom)
				(hide yes)
			)
		)
		(property "License" "Apache-2.0"
			(at 279.4 212.09 0)
			(effects
				(font
					(size 1.27 1.27)
					(thickness 0.15)
				)
				(justify left bottom)
				(hide yes)
			)
		)
		(pin "1"
		)
		(instances
			(project "data-center-rdimm-ddr5-tester"
				(path ""
					(reference "#PWR0203")
					(unit 1)
				)
			)
		)
	)
	(symbol
		(lib_id "antmicroCapacitors0402:C_100n_0402")
		(at 271.78 99.06 90)
		(unit 1)
		(exclude_from_sim no)
		(in_bom yes)
		(on_board yes)
		(dnp no)
		(fields_autoplaced yes)
		(property "Reference" "C6"
			(at 274.955 95.2435 90)
			(effects
				(font
					(size 1.27 1.27)
					(thickness 0.15)
				)
				(justify right)
			)
		)
		(property "Value" "C_100n_0402"
			(at 281.94 78.74 0)
			(effects
				(font
					(size 1.27 1.27)
					(thickness 0.15)
				)
				(justify left bottom)
				(hide yes)
			)
		)
		(property "Footprint" "antmicro-footprints:C_0402_1005Metric"
			(at 284.48 78.74 0)
			(effects
				(font
					(size 1.27 1.27)
					(thickness 0.15)
				)
				(justify left bottom)
				(hide yes)
			)
		)
		(property "Datasheet" "https://www.murata.com/products/productdetail?partno=GRM155R61H104KE14%23"
			(at 287.02 78.74 0)
			(effects
				(font
					(size 1.27 1.27)
					(thickness 0.15)
				)
				(justify left bottom)
				(hide yes)
			)
		)
		(property "Description" ""
			(at 271.78 99.06 0)
			(effects
				(font
					(size 1.27 1.27)
				)
				(hide yes)
			)
		)
		(property "MPN" "GRM155R61H104KE14D"
			(at 289.56 78.74 0)
			(effects
				(font
					(size 1.27 1.27)
					(thickness 0.15)
				)
				(justify left bottom)
				(hide yes)
			)
		)
		(property "Manufacturer" "Murata"
			(at 292.1 78.74 0)
			(effects
				(font
					(size 1.27 1.27)
					(thickness 0.15)
				)
				(justify left bottom)
				(hide yes)
			)
		)
		(property "License" "Apache-2.0"
			(at 294.64 78.74 0)
			(effects
				(font
					(size 1.27 1.27)
					(thickness 0.15)
				)
				(justify left bottom)
				(hide yes)
			)
		)
		(property "Author" "Antmicro"
			(at 297.18 78.74 0)
			(effects
				(font
					(size 1.27 1.27)
					(thickness 0.15)
				)
				(justify left bottom)
				(hide yes)
			)
		)
		(property "Val" "100n"
			(at 274.955 97.7835 90)
			(effects
				(font
					(size 1.27 1.27)
					(thickness 0.15)
				)
				(justify right)
			)
		)
		(property "Voltage" "50V"
			(at 299.72 78.74 0)
			(effects
				(font
					(size 1.27 1.27)
				)
				(justify left bottom)
				(hide yes)
			)
		)
		(property "Dielectric" "X5R"
			(at 302.26 78.74 0)
			(effects
				(font
					(size 1.27 1.27)
				)
				(justify left bottom)
				(hide yes)
			)
		)
		(pin "1"
		)
		(pin "2"
		)
		(instances
			(project "data-center-rdimm-ddr5-tester"
				(path ""
					(reference "C6")
					(unit 1)
				)
			)
		)
	)
	(symbol
		(lib_id "antmicropower:VDD")
		(at 364.49 232.41 0)
		(unit 1)
		(exclude_from_sim no)
		(in_bom yes)
		(on_board yes)
		(dnp no)
		(fields_autoplaced yes)
		(property "Reference" "#PWR044"
			(at 364.49 236.22 0)
			(effects
				(font
					(size 1.27 1.27)
				)
				(hide yes)
			)
		)
		(property "Value" "VDDQ"
			(at 364.49 227.33 0)
			(effects
				(font
					(size 1.27 1.27)
				)
			)
		)
		(property "Footprint" ""
			(at 364.49 232.41 0)
			(effects
				(font
					(size 1.27 1.27)
				)
				(hide yes)
			)
		)
		(property "Datasheet" ""
			(at 364.49 232.41 0)
			(effects
				(font
					(size 1.27 1.27)
				)
				(hide yes)
			)
		)
		(property "Description" ""
			(at 364.49 232.41 0)
			(effects
				(font
					(size 1.27 1.27)
				)
				(hide yes)
			)
		)
		(pin "1"
		)
		(instances
			(project "data-center-rdimm-ddr5-tester"
				(path ""
					(reference "#PWR044")
					(unit 1)
				)
			)
		)
	)
	(symbol
		(lib_id "antmicropower:GND")
		(at 248.92 48.26 0)
		(unit 1)
		(exclude_from_sim no)
		(in_bom yes)
		(on_board yes)
		(dnp no)
		(fields_autoplaced yes)
		(property "Reference" "#PWR033"
			(at 248.92 54.61 0)
			(effects
				(font
					(size 1.27 1.27)
				)
				(hide yes)
			)
		)
		(property "Value" "GND"
			(at 247.015 52.705 0)
			(effects
				(font
					(size 1.27 1.27)
					(thickness 0.15)
				)
				(justify left bottom)
			)
		)
		(property "Footprint" ""
			(at 257.81 55.88 0)
			(effects
				(font
					(size 1.27 1.27)
					(thickness 0.15)
				)
				(justify left bottom)
				(hide yes)
			)
		)
		(property "Datasheet" ""
			(at 257.81 60.96 0)
			(effects
				(font
					(size 1.27 1.27)
					(thickness 0.15)
				)
				(justify left bottom)
				(hide yes)
			)
		)
		(property "Description" ""
			(at 248.92 48.26 0)
			(effects
				(font
					(size 1.27 1.27)
				)
				(hide yes)
			)
		)
		(property "Author" "Antmicro"
			(at 257.81 53.34 0)
			(effects
				(font
					(size 1.27 1.27)
					(thickness 0.15)
				)
				(justify left bottom)
				(hide yes)
			)
		)
		(property "License" "Apache-2.0"
			(at 257.81 55.88 0)
			(effects
				(font
					(size 1.27 1.27)
					(thickness 0.15)
				)
				(justify left bottom)
				(hide yes)
			)
		)
		(pin "1"
		)
		(instances
			(project "data-center-rdimm-ddr5-tester"
				(path ""
					(reference "#PWR033")
					(unit 1)
				)
			)
		)
	)
	(symbol
		(lib_id "antmicroCapacitors0402:C_1u_0402")
		(at 356.87 175.26 270)
		(unit 1)
		(exclude_from_sim no)
		(in_bom no)
		(on_board yes)
		(dnp yes)
		(property "Reference" "C127"
			(at 360.045 176.53 90)
			(effects
				(font
					(size 1.27 1.27)
				)
				(justify left)
			)
		)
		(property "Value" "C_1u_0402"
			(at 346.71 195.58 0)
			(effects
				(font
					(size 1.27 1.27)
					(thickness 0.15)
				)
				(justify left bottom)
				(hide yes)
			)
		)
		(property "Footprint" "antmicro-footprints:C_0402_1005Metric"
			(at 344.17 195.58 0)
			(effects
				(font
					(size 1.27 1.27)
					(thickness 0.15)
				)
				(justify left bottom)
				(hide yes)
			)
		)
		(property "Datasheet" "https://product.tdk.com/en/search/capacitor/ceramic/mlcc/info?part_no=C1005X6S1A105K050BC"
			(at 341.63 195.58 0)
			(effects
				(font
					(size 1.27 1.27)
					(thickness 0.15)
				)
				(justify left bottom)
				(hide yes)
			)
		)
		(property "Description" ""
			(at 356.87 175.26 0)
			(effects
				(font
					(size 1.27 1.27)
				)
				(hide yes)
			)
		)
		(property "Manufacturer" "TDK"
			(at 336.55 195.58 0)
			(effects
				(font
					(size 1.27 1.27)
					(thickness 0.15)
				)
				(justify left bottom)
				(hide yes)
			)
		)
		(property "MPN" "C1005X6S1A105K050BC"
			(at 339.09 195.58 0)
			(effects
				(font
					(size 1.27 1.27)
					(thickness 0.15)
				)
				(justify left bottom)
				(hide yes)
			)
		)
		(property "Val" "1u"
			(at 360.045 178.4412 90)
			(effects
				(font
					(size 1.27 1.27)
					(thickness 0.15)
				)
				(justify left)
			)
		)
		(property "License" "Apache-2.0"
			(at 334.01 195.58 0)
			(effects
				(font
					(size 1.27 1.27)
					(thickness 0.15)
				)
				(justify left bottom)
				(hide yes)
			)
		)
		(property "Author" "Antmicro"
			(at 331.47 195.58 0)
			(effects
				(font
					(size 1.27 1.27)
					(thickness 0.15)
				)
				(justify left bottom)
				(hide yes)
			)
		)
		(property "Voltage" ""
			(at 328.93 195.58 0)
			(effects
				(font
					(size 1.27 1.27)
				)
				(justify left bottom)
				(hide yes)
			)
		)
		(property "Dielectric" ""
			(at 326.39 195.58 0)
			(effects
				(font
					(size 1.27 1.27)
				)
				(justify left bottom)
				(hide yes)
			)
		)
		(pin "1"
		)
		(pin "2"
		)
		(instances
			(project "data-center-rdimm-ddr5-tester"
				(path ""
					(reference "C127")
					(unit 1)
				)
			)
		)
	)
	(symbol
		(lib_id "antmicroLEDIndicationDiscrete:LED_G_0402_VLMTG1500-GS08")
		(at 248.92 90.17 90)
		(unit 1)
		(exclude_from_sim no)
		(in_bom yes)
		(on_board yes)
		(dnp no)
		(fields_autoplaced yes)
		(property "Reference" "D22"
			(at 250.825 86.36 90)
			(effects
				(font
					(size 1.27 1.27)
					(thickness 0.15)
				)
				(justify right)
			)
		)
		(property "Value" "LED_G_0402_VLMTG1500-GS08"
			(at 256.54 67.31 0)
			(effects
				(font
					(size 1.27 1.27)
					(thickness 0.15)
				)
				(justify left bottom)
				(hide yes)
			)
		)
		(property "Footprint" "antmicro-footprints:LED_0402_1005Metric_G"
			(at 259.08 67.31 0)
			(effects
				(font
					(size 1.27 1.27)
					(thickness 0.15)
				)
				(justify left bottom)
				(hide yes)
			)
		)
		(property "Datasheet" "https://www.vishay.com/docs/82554/vlmo1500.pdf"
			(at 261.62 67.31 0)
			(effects
				(font
					(size 1.27 1.27)
					(thickness 0.15)
				)
				(justify left bottom)
				(hide yes)
			)
		)
		(property "Description" ""
			(at 248.92 90.17 0)
			(effects
				(font
					(size 1.27 1.27)
				)
				(hide yes)
			)
		)
		(property "MPN" "VLMTG1500-GS08"
			(at 264.16 67.31 0)
			(effects
				(font
					(size 1.27 1.27)
					(thickness 0.15)
				)
				(justify left bottom)
				(hide yes)
			)
		)
		(property "Manufacturer" "Vishay"
			(at 266.7 67.31 0)
			(effects
				(font
					(size 1.27 1.27)
					(thickness 0.15)
				)
				(justify left bottom)
				(hide yes)
			)
		)
		(property "Color" "Green"
			(at 250.825 88.9 90)
			(effects
				(font
					(size 1.27 1.27)
				)
				(justify right)
			)
		)
		(property "Author" "Antmicro"
			(at 269.24 67.31 0)
			(effects
				(font
					(size 1.27 1.27)
					(thickness 0.15)
				)
				(justify left bottom)
				(hide yes)
			)
		)
		(property "License" "Apache-2.0"
			(at 271.78 67.31 0)
			(effects
				(font
					(size 1.27 1.27)
					(thickness 0.15)
				)
				(justify left bottom)
				(hide yes)
			)
		)
		(pin "1"
		)
		(pin "2"
		)
		(instances
			(project "data-center-rdimm-ddr5-tester"
				(path ""
					(reference "D22")
					(unit 1)
				)
			)
		)
	)
	(symbol
		(lib_id "antmicroMemoryConnectorsPCCardSockets:Bus_DDR5_DDR504111002KQ")
		(at 85.09 63.5 0)
		(unit 1)
		(exclude_from_sim no)
		(in_bom yes)
		(on_board yes)
		(dnp no)
		(fields_autoplaced yes)
		(property "Reference" "J2"
			(at 100.33 56.515 0)
			(effects
				(font
					(size 1.27 1.27)
					(thickness 0.15)
				)
			)
		)
		(property "Value" "Bus_DDR5_DDR504111002KQ"
			(at 130.81 68.58 0)
			(effects
				(font
					(size 1.27 1.27)
					(thickness 0.15)
				)
				(justify left bottom)
				(hide yes)
			)
		)
		(property "Footprint" "antmicro-footprints:Bus_DDR5_Socket_Amphenol_DDR504111002KQ"
			(at 130.81 71.12 0)
			(effects
				(font
					(size 1.27 1.27)
					(thickness 0.15)
				)
				(justify left bottom)
				(hide yes)
			)
		)
		(property "Datasheet" "https://www.amphenol-icc.com/ddr5-smt-ddr504111002kq.html"
			(at 130.81 73.66 0)
			(effects
				(font
					(size 1.27 1.27)
					(thickness 0.15)
				)
				(justify left bottom)
				(hide yes)
			)
		)
		(property "Description" ""
			(at 85.09 63.5 0)
			(effects
				(font
					(size 1.27 1.27)
				)
				(hide yes)
			)
		)
		(property "Manufacturer" "Amphenol"
			(at 130.81 76.2 0)
			(effects
				(font
					(size 1.27 1.27)
					(thickness 0.15)
				)
				(justify left bottom)
				(hide yes)
			)
		)
		(property "MPN" "DDR504111002KQ"
			(at 100.33 59.055 0)
			(effects
				(font
					(size 1.27 1.27)
					(thickness 0.15)
				)
			)
		)
		(property "Author" "Antmicro"
			(at 130.81 81.28 0)
			(effects
				(font
					(size 1.27 1.27)
					(thickness 0.15)
				)
				(justify left bottom)
				(hide yes)
			)
		)
		(property "License" "Apache-2.0"
			(at 130.81 83.82 0)
			(effects
				(font
					(size 1.27 1.27)
					(thickness 0.15)
				)
				(justify left bottom)
				(hide yes)
			)
		)
		(pin "41"
		)
		(pin "182"
		)
		(pin "233"
		)
		(pin "39"
		)
		(pin "58"
		)
		(pin "214"
		)
		(pin "219"
		)
		(pin "237"
		)
		(pin "131"
		)
		(pin "159"
		)
		(pin "10"
		)
		(pin "55"
		)
		(pin "45"
		)
		(pin "91"
		)
		(pin "94"
		)
		(pin "257"
		)
		(pin "134"
		)
		(pin "284"
		)
		(pin "189"
		)
		(pin "281"
		)
		(pin "31"
		)
		(pin "188"
		)
		(pin "193"
		)
		(pin "217"
		)
		(pin "177"
		)
		(pin "215"
		)
		(pin "195"
		)
		(pin "143"
		)
		(pin "262"
		)
		(pin "218"
		)
		(pin "29"
		)
		(pin "30"
		)
		(pin "3"
		)
		(pin "278"
		)
		(pin "280"
		)
		(pin "286"
		)
		(pin "282"
		)
		(pin "186"
		)
		(pin "132"
		)
		(pin "251"
		)
		(pin "249"
		)
		(pin "111"
		)
		(pin "49"
		)
		(pin "139"
		)
		(pin "207"
		)
		(pin "247"
		)
		(pin "56"
		)
		(pin "165"
		)
		(pin "228"
		)
		(pin "213"
		)
		(pin "141"
		)
		(pin "287"
		)
		(pin "48"
		)
		(pin "192"
		)
		(pin "171"
		)
		(pin "197"
		)
		(pin "258"
		)
		(pin "157"
		)
		(pin "47"
		)
		(pin "232"
		)
		(pin "163"
		)
		(pin "196"
		)
		(pin "43"
		)
		(pin "89"
		)
		(pin "227"
		)
		(pin "26"
		)
		(pin "125"
		)
		(pin "46"
		)
		(pin "136"
		)
		(pin "51"
		)
		(pin "271"
		)
		(pin "133"
		)
		(pin "274"
		)
		(pin "9"
		)
		(pin "98"
		)
		(pin "259"
		)
		(pin "277"
		)
		(pin "170"
		)
		(pin "160"
		)
		(pin "236"
		)
		(pin "93"
		)
		(pin "145"
		)
		(pin "283"
		)
		(pin "230"
		)
		(pin "238"
		)
		(pin "184"
		)
		(pin "53"
		)
		(pin "288"
		)
		(pin "1"
		)
		(pin "35"
		)
		(pin "235"
		)
		(pin "191"
		)
		(pin "5"
		)
		(pin "190"
		)
		(pin "211"
		)
		(pin "216"
		)
		(pin "285"
		)
		(pin "250"
		)
		(pin "146"
		)
		(pin "264"
		)
		(pin "2"
		)
		(pin "7"
		)
		(pin "114"
		)
		(pin "147"
		)
		(pin "16"
		)
		(pin "120"
		)
		(pin "17"
		)
		(pin "96"
		)
		(pin "167"
		)
		(pin "14"
		)
		(pin "144"
		)
		(pin "19"
		)
		(pin "180"
		)
		(pin "155"
		)
		(pin "240"
		)
		(pin "126"
		)
		(pin "152"
		)
		(pin "231"
		)
		(pin "253"
		)
		(pin "113"
		)
		(pin "201"
		)
		(pin "15"
		)
		(pin "117"
		)
		(pin "67"
		)
		(pin "24"
		)
		(pin "124"
		)
		(pin "187"
		)
		(pin "263"
		)
		(pin "199"
		)
		(pin "42"
		)
		(pin "38"
		)
		(pin "183"
		)
		(pin "204"
		)
		(pin "36"
		)
		(pin "32"
		)
		(pin "185"
		)
		(pin "276"
		)
		(pin "156"
		)
		(pin "248"
		)
		(pin "252"
		)
		(pin "164"
		)
		(pin "243"
		)
		(pin "245"
		)
		(pin "209"
		)
		(pin "208"
		)
		(pin "272"
		)
		(pin "169"
		)
		(pin "166"
		)
		(pin "127"
		)
		(pin "161"
		)
		(pin "140"
		)
		(pin "28"
		)
		(pin "135"
		)
		(pin "206"
		)
		(pin "261"
		)
		(pin "239"
		)
		(pin "224"
		)
		(pin "246"
		)
		(pin "44"
		)
		(pin "198"
		)
		(pin "212"
		)
		(pin "241"
		)
		(pin "162"
		)
		(pin "129"
		)
		(pin "11"
		)
		(pin "194"
		)
		(pin "13"
		)
		(pin "210"
		)
		(pin "149"
		)
		(pin "123"
		)
		(pin "229"
		)
		(pin "130"
		)
		(pin "148"
		)
		(pin "173"
		)
		(pin "255"
		)
		(pin "40"
		)
		(pin "244"
		)
		(pin "138"
		)
		(pin "115"
		)
		(pin "25"
		)
		(pin "200"
		)
		(pin "21"
		)
		(pin "128"
		)
		(pin "104"
		)
		(pin "266"
		)
		(pin "83"
		)
		(pin "84"
		)
		(pin "S1"
		)
		(pin "81"
		)
		(pin "82"
		)
		(pin "87"
		)
		(pin "86"
		)
		(pin "69"
		)
		(pin "88"
		)
		(pin "90"
		)
		(pin "92"
		)
		(pin "97"
		)
		(pin "95"
		)
		(pin "99"
		)
		(pin "85"
		)
		(pin "73"
		)
		(pin "S3"
		)
		(pin "77"
		)
		(pin "75"
		)
		(pin "76"
		)
		(pin "74"
		)
		(pin "78"
		)
		(pin "80"
		)
		(pin "8"
		)
		(pin "S2"
		)
		(pin "71"
		)
		(pin "79"
		)
		(pin "68"
		)
		(pin "72"
		)
		(pin "70"
		)
		(pin "60"
		)
		(pin "34"
		)
		(pin "27"
		)
		(pin "279"
		)
		(pin "175"
		)
		(pin "121"
		)
		(pin "150"
		)
		(pin "242"
		)
		(pin "158"
		)
		(pin "268"
		)
		(pin "65"
		)
		(pin "52"
		)
		(pin "33"
		)
		(pin "256"
		)
		(pin "168"
		)
		(pin "50"
		)
		(pin "100"
		)
		(pin "174"
		)
		(pin "176"
		)
		(pin "178"
		)
		(pin "153"
		)
		(pin "203"
		)
		(pin "205"
		)
		(pin "179"
		)
		(pin "18"
		)
		(pin "181"
		)
		(pin "221"
		)
		(pin "222"
		)
		(pin "223"
		)
		(pin "273"
		)
		(pin "22"
		)
		(pin "23"
		)
		(pin "275"
		)
		(pin "234"
		)
		(pin "137"
		)
		(pin "63"
		)
		(pin "62"
		)
		(pin "61"
		)
		(pin "6"
		)
		(pin "59"
		)
		(pin "57"
		)
		(pin "54"
		)
		(pin "103"
		)
		(pin "101"
		)
		(pin "116"
		)
		(pin "118"
		)
		(pin "12"
		)
		(pin "66"
		)
		(pin "64"
		)
		(pin "260"
		)
		(pin "269"
		)
		(pin "4"
		)
		(pin "202"
		)
		(pin "225"
		)
		(pin "142"
		)
		(pin "37"
		)
		(pin "110"
		)
		(pin "254"
		)
		(pin "112"
		)
		(pin "119"
		)
		(pin "108"
		)
		(pin "106"
		)
		(pin "151"
		)
		(pin "102"
		)
		(pin "172"
		)
		(pin "105"
		)
		(pin "154"
		)
		(pin "220"
		)
		(pin "270"
		)
		(pin "267"
		)
		(pin "122"
		)
		(pin "109"
		)
		(pin "107"
		)
		(pin "265"
		)
		(pin "20"
		)
		(pin "226"
		)
		(instances
			(project "data-center-rdimm-ddr5-tester"
				(path ""
					(reference "J2")
					(unit 1)
				)
			)
		)
	)
	(symbol
		(lib_id "antmicroMemoryConnectorsPCCardSockets:Bus_DDR5_DDR504111002KQ_CUSTOM_1xDetectPin")
		(at 323.85 36.83 0)
		(unit 2)
		(exclude_from_sim no)
		(in_bom yes)
		(on_board yes)
		(dnp no)
		(fields_autoplaced yes)
		(property "Reference" "J2"
			(at 339.09 29.21 0)
			(effects
				(font
					(size 1.27 1.27)
					(thickness 0.15)
				)
			)
		)
		(property "Value" "Bus_DDR5_DDR504111002KQ"
			(at 369.57 41.91 0)
			(effects
				(font
					(size 1.27 1.27)
					(thickness 0.15)
				)
				(justify left bottom)
				(hide yes)
			)
		)
		(property "Footprint" "antmicro-footprints:Bus_DDR5_Socket_Amphenol_DDR504111002KQ"
			(at 369.57 44.45 0)
			(effects
				(font
					(size 1.27 1.27)
					(thickness 0.15)
				)
				(justify left bottom)
				(hide yes)
			)
		)
		(property "Datasheet" "https://www.amphenol-icc.com/ddr5-smt-ddr504111002kq.html"
			(at 369.57 46.99 0)
			(effects
				(font
					(size 1.27 1.27)
					(thickness 0.15)
				)
				(justify left bottom)
				(hide yes)
			)
		)
		(property "Description" ""
			(at 323.85 36.83 0)
			(effects
				(font
					(size 1.27 1.27)
				)
				(hide yes)
			)
		)
		(property "Manufacturer" "Amphenol"
			(at 369.57 49.53 0)
			(effects
				(font
					(size 1.27 1.27)
					(thickness 0.15)
				)
				(justify left bottom)
				(hide yes)
			)
		)
		(property "MPN" "DDR504111002KQ"
			(at 339.09 31.75 0)
			(effects
				(font
					(size 1.27 1.27)
					(thickness 0.15)
				)
			)
		)
		(property "Author" "Antmicro"
			(at 369.57 54.61 0)
			(effects
				(font
					(size 1.27 1.27)
					(thickness 0.15)
				)
				(justify left bottom)
				(hide yes)
			)
		)
		(property "License" "Apache-2.0"
			(at 369.57 57.15 0)
			(effects
				(font
					(size 1.27 1.27)
					(thickness 0.15)
				)
				(justify left bottom)
				(hide yes)
			)
		)
		(pin "41"
		)
		(pin "182"
		)
		(pin "233"
		)
		(pin "39"
		)
		(pin "58"
		)
		(pin "214"
		)
		(pin "219"
		)
		(pin "237"
		)
		(pin "131"
		)
		(pin "159"
		)
		(pin "10"
		)
		(pin "55"
		)
		(pin "45"
		)
		(pin "91"
		)
		(pin "94"
		)
		(pin "257"
		)
		(pin "134"
		)
		(pin "284"
		)
		(pin "189"
		)
		(pin "281"
		)
		(pin "31"
		)
		(pin "188"
		)
		(pin "193"
		)
		(pin "217"
		)
		(pin "177"
		)
		(pin "215"
		)
		(pin "195"
		)
		(pin "143"
		)
		(pin "262"
		)
		(pin "218"
		)
		(pin "29"
		)
		(pin "30"
		)
		(pin "3"
		)
		(pin "278"
		)
		(pin "280"
		)
		(pin "286"
		)
		(pin "282"
		)
		(pin "186"
		)
		(pin "132"
		)
		(pin "251"
		)
		(pin "249"
		)
		(pin "111"
		)
		(pin "49"
		)
		(pin "139"
		)
		(pin "207"
		)
		(pin "247"
		)
		(pin "56"
		)
		(pin "165"
		)
		(pin "228"
		)
		(pin "213"
		)
		(pin "141"
		)
		(pin "287"
		)
		(pin "48"
		)
		(pin "192"
		)
		(pin "171"
		)
		(pin "197"
		)
		(pin "258"
		)
		(pin "157"
		)
		(pin "47"
		)
		(pin "232"
		)
		(pin "163"
		)
		(pin "196"
		)
		(pin "43"
		)
		(pin "89"
		)
		(pin "227"
		)
		(pin "26"
		)
		(pin "125"
		)
		(pin "46"
		)
		(pin "136"
		)
		(pin "51"
		)
		(pin "271"
		)
		(pin "133"
		)
		(pin "274"
		)
		(pin "9"
		)
		(pin "98"
		)
		(pin "259"
		)
		(pin "277"
		)
		(pin "170"
		)
		(pin "160"
		)
		(pin "236"
		)
		(pin "93"
		)
		(pin "145"
		)
		(pin "283"
		)
		(pin "230"
		)
		(pin "238"
		)
		(pin "184"
		)
		(pin "53"
		)
		(pin "288"
		)
		(pin "1"
		)
		(pin "35"
		)
		(pin "235"
		)
		(pin "191"
		)
		(pin "5"
		)
		(pin "190"
		)
		(pin "211"
		)
		(pin "216"
		)
		(pin "285"
		)
		(pin "250"
		)
		(pin "146"
		)
		(pin "264"
		)
		(pin "2"
		)
		(pin "7"
		)
		(pin "114"
		)
		(pin "147"
		)
		(pin "16"
		)
		(pin "120"
		)
		(pin "17"
		)
		(pin "96"
		)
		(pin "167"
		)
		(pin "14"
		)
		(pin "144"
		)
		(pin "19"
		)
		(pin "180"
		)
		(pin "155"
		)
		(pin "240"
		)
		(pin "126"
		)
		(pin "152"
		)
		(pin "231"
		)
		(pin "253"
		)
		(pin "113"
		)
		(pin "201"
		)
		(pin "15"
		)
		(pin "117"
		)
		(pin "67"
		)
		(pin "24"
		)
		(pin "124"
		)
		(pin "187"
		)
		(pin "263"
		)
		(pin "199"
		)
		(pin "42"
		)
		(pin "38"
		)
		(pin "183"
		)
		(pin "204"
		)
		(pin "36"
		)
		(pin "32"
		)
		(pin "185"
		)
		(pin "276"
		)
		(pin "156"
		)
		(pin "248"
		)
		(pin "252"
		)
		(pin "164"
		)
		(pin "243"
		)
		(pin "245"
		)
		(pin "209"
		)
		(pin "208"
		)
		(pin "272"
		)
		(pin "169"
		)
		(pin "166"
		)
		(pin "127"
		)
		(pin "161"
		)
		(pin "140"
		)
		(pin "28"
		)
		(pin "135"
		)
		(pin "206"
		)
		(pin "261"
		)
		(pin "239"
		)
		(pin "224"
		)
		(pin "246"
		)
		(pin "44"
		)
		(pin "198"
		)
		(pin "212"
		)
		(pin "241"
		)
		(pin "162"
		)
		(pin "129"
		)
		(pin "11"
		)
		(pin "194"
		)
		(pin "13"
		)
		(pin "210"
		)
		(pin "149"
		)
		(pin "123"
		)
		(pin "229"
		)
		(pin "130"
		)
		(pin "148"
		)
		(pin "173"
		)
		(pin "255"
		)
		(pin "40"
		)
		(pin "244"
		)
		(pin "138"
		)
		(pin "115"
		)
		(pin "25"
		)
		(pin "200"
		)
		(pin "21"
		)
		(pin "128"
		)
		(pin "104"
		)
		(pin "266"
		)
		(pin "83"
		)
		(pin "84"
		)
		(pin "S1"
		)
		(pin "81"
		)
		(pin "82"
		)
		(pin "87"
		)
		(pin "86"
		)
		(pin "69"
		)
		(pin "88"
		)
		(pin "90"
		)
		(pin "92"
		)
		(pin "97"
		)
		(pin "95"
		)
		(pin "99"
		)
		(pin "85"
		)
		(pin "73"
		)
		(pin "S3"
		)
		(pin "77"
		)
		(pin "75"
		)
		(pin "76"
		)
		(pin "74"
		)
		(pin "78"
		)
		(pin "80"
		)
		(pin "8"
		)
		(pin "S2"
		)
		(pin "71"
		)
		(pin "79"
		)
		(pin "68"
		)
		(pin "72"
		)
		(pin "70"
		)
		(pin "60"
		)
		(pin "34"
		)
		(pin "27"
		)
		(pin "279"
		)
		(pin "175"
		)
		(pin "121"
		)
		(pin "150"
		)
		(pin "242"
		)
		(pin "158"
		)
		(pin "268"
		)
		(pin "65"
		)
		(pin "52"
		)
		(pin "33"
		)
		(pin "256"
		)
		(pin "168"
		)
		(pin "50"
		)
		(pin "100"
		)
		(pin "174"
		)
		(pin "176"
		)
		(pin "178"
		)
		(pin "153"
		)
		(pin "203"
		)
		(pin "205"
		)
		(pin "179"
		)
		(pin "18"
		)
		(pin "181"
		)
		(pin "221"
		)
		(pin "222"
		)
		(pin "223"
		)
		(pin "273"
		)
		(pin "22"
		)
		(pin "23"
		)
		(pin "275"
		)
		(pin "234"
		)
		(pin "137"
		)
		(pin "63"
		)
		(pin "62"
		)
		(pin "61"
		)
		(pin "6"
		)
		(pin "59"
		)
		(pin "57"
		)
		(pin "54"
		)
		(pin "103"
		)
		(pin "101"
		)
		(pin "116"
		)
		(pin "118"
		)
		(pin "12"
		)
		(pin "66"
		)
		(pin "64"
		)
		(pin "260"
		)
		(pin "269"
		)
		(pin "4"
		)
		(pin "202"
		)
		(pin "225"
		)
		(pin "142"
		)
		(pin "37"
		)
		(pin "110"
		)
		(pin "254"
		)
		(pin "112"
		)
		(pin "119"
		)
		(pin "108"
		)
		(pin "106"
		)
		(pin "151"
		)
		(pin "102"
		)
		(pin "172"
		)
		(pin "105"
		)
		(pin "154"
		)
		(pin "220"
		)
		(pin "270"
		)
		(pin "267"
		)
		(pin "122"
		)
		(pin "109"
		)
		(pin "107"
		)
		(pin "265"
		)
		(pin "20"
		)
		(pin "226"
		)
		(instances
			(project "data-center-rdimm-ddr5-tester"
				(path ""
					(reference "J2")
					(unit 2)
				)
			)
		)
	)
	(symbol
		(lib_id "antmicropower:+3V3")
		(at 347.98 158.75 0)
		(unit 1)
		(exclude_from_sim no)
		(in_bom yes)
		(on_board yes)
		(dnp no)
		(fields_autoplaced yes)
		(property "Reference" "#PWR0210"
			(at 347.98 162.56 0)
			(effects
				(font
					(size 1.27 1.27)
				)
				(hide yes)
			)
		)
		(property "Value" "+3V3"
			(at 344.805 156.21 0)
			(effects
				(font
					(size 1.27 1.27)
					(thickness 0.15)
				)
				(justify left bottom)
			)
		)
		(property "Footprint" ""
			(at 363.22 166.37 0)
			(effects
				(font
					(size 1.27 1.27)
					(thickness 0.15)
				)
				(justify left bottom)
				(hide yes)
			)
		)
		(property "Datasheet" ""
			(at 363.22 168.91 0)
			(effects
				(font
					(size 1.27 1.27)
					(thickness 0.15)
				)
				(justify left bottom)
				(hide yes)
			)
		)
		(property "Description" ""
			(at 347.98 158.75 0)
			(effects
				(font
					(size 1.27 1.27)
				)
				(hide yes)
			)
		)
		(property "Author" "Antmicro"
			(at 363.22 161.29 0)
			(effects
				(font
					(size 1.27 1.27)
					(thickness 0.15)
				)
				(justify left bottom)
				(hide yes)
			)
		)
		(property "License" "Apache-2.0"
			(at 363.22 163.83 0)
			(effects
				(font
					(size 1.27 1.27)
					(thickness 0.15)
				)
				(justify left bottom)
				(hide yes)
			)
		)
		(pin "1"
		)
		(instances
			(project "data-center-rdimm-ddr5-tester"
				(path ""
					(reference "#PWR0210")
					(unit 1)
				)
			)
		)
	)
	(symbol
		(lib_id "antmicroLEDIndicationDiscrete:LED_G_0402_VLMTG1500-GS08")
		(at 248.92 39.37 90)
		(unit 1)
		(exclude_from_sim no)
		(in_bom yes)
		(on_board yes)
		(dnp no)
		(fields_autoplaced yes)
		(property "Reference" "D21"
			(at 250.825 35.56 90)
			(effects
				(font
					(size 1.27 1.27)
					(thickness 0.15)
				)
				(justify right)
			)
		)
		(property "Value" "LED_G_0402_VLMTG1500-GS08"
			(at 256.54 16.51 0)
			(effects
				(font
					(size 1.27 1.27)
					(thickness 0.15)
				)
				(justify left bottom)
				(hide yes)
			)
		)
		(property "Footprint" "antmicro-footprints:LED_0402_1005Metric_G"
			(at 259.08 16.51 0)
			(effects
				(font
					(size 1.27 1.27)
					(thickness 0.15)
				)
				(justify left bottom)
				(hide yes)
			)
		)
		(property "Datasheet" "https://www.vishay.com/docs/82554/vlmo1500.pdf"
			(at 261.62 16.51 0)
			(effects
				(font
					(size 1.27 1.27)
					(thickness 0.15)
				)
				(justify left bottom)
				(hide yes)
			)
		)
		(property "Description" ""
			(at 248.92 39.37 0)
			(effects
				(font
					(size 1.27 1.27)
				)
				(hide yes)
			)
		)
		(property "MPN" "VLMTG1500-GS08"
			(at 264.16 16.51 0)
			(effects
				(font
					(size 1.27 1.27)
					(thickness 0.15)
				)
				(justify left bottom)
				(hide yes)
			)
		)
		(property "Manufacturer" "Vishay"
			(at 266.7 16.51 0)
			(effects
				(font
					(size 1.27 1.27)
					(thickness 0.15)
				)
				(justify left bottom)
				(hide yes)
			)
		)
		(property "Color" "Green"
			(at 250.825 38.1 90)
			(effects
				(font
					(size 1.27 1.27)
				)
				(justify right)
			)
		)
		(property "Author" "Antmicro"
			(at 269.24 16.51 0)
			(effects
				(font
					(size 1.27 1.27)
					(thickness 0.15)
				)
				(justify left bottom)
				(hide yes)
			)
		)
		(property "License" "Apache-2.0"
			(at 271.78 16.51 0)
			(effects
				(font
					(size 1.27 1.27)
					(thickness 0.15)
				)
				(justify left bottom)
				(hide yes)
			)
		)
		(pin "1"
		)
		(pin "2"
		)
		(instances
			(project "data-center-rdimm-ddr5-tester"
				(path ""
					(reference "D21")
					(unit 1)
				)
			)
		)
	)
	(symbol
		(lib_id "antmicroResistors0402:R_47k_0402")
		(at 215.9 90.17 90)
		(unit 1)
		(exclude_from_sim no)
		(in_bom yes)
		(on_board yes)
		(dnp no)
		(fields_autoplaced yes)
		(property "Reference" "R244"
			(at 218.44 86.36 90)
			(effects
				(font
					(size 1.27 1.27)
					(thickness 0.15)
				)
				(justify right)
			)
		)
		(property "Value" "R_47k_0402"
			(at 228.6 69.85 0)
			(effects
				(font
					(size 1.27 1.27)
					(thickness 0.15)
				)
				(justify left bottom)
				(hide yes)
			)
		)
		(property "Footprint" "antmicro-footprints:R_0402_1005Metric"
			(at 231.14 69.85 0)
			(effects
				(font
					(size 1.27 1.27)
					(thickness 0.15)
				)
				(justify left bottom)
				(hide yes)
			)
		)
		(property "Datasheet" "https://www.bourns.com/docs/product-datasheets/cr.pdf"
			(at 233.68 69.85 0)
			(effects
				(font
					(size 1.27 1.27)
					(thickness 0.15)
				)
				(justify left bottom)
				(hide yes)
			)
		)
		(property "Description" ""
			(at 215.9 90.17 0)
			(effects
				(font
					(size 1.27 1.27)
				)
				(hide yes)
			)
		)
		(property "MPN" "CR0402-FX-4702GLF"
			(at 236.22 69.85 0)
			(effects
				(font
					(size 1.27 1.27)
					(thickness 0.15)
				)
				(justify left bottom)
				(hide yes)
			)
		)
		(property "Manufacturer" "Bourns"
			(at 238.76 69.85 0)
			(effects
				(font
					(size 1.27 1.27)
					(thickness 0.15)
				)
				(justify left bottom)
				(hide yes)
			)
		)
		(property "License" "Apache-2.0"
			(at 241.3 69.85 0)
			(effects
				(font
					(size 1.27 1.27)
					(thickness 0.15)
				)
				(justify left bottom)
				(hide yes)
			)
		)
		(property "Author" "Antmicro"
			(at 243.84 69.85 0)
			(effects
				(font
					(size 1.27 1.27)
					(thickness 0.15)
				)
				(justify left bottom)
				(hide yes)
			)
		)
		(property "Val" "47k"
			(at 218.44 88.9 90)
			(effects
				(font
					(size 1.27 1.27)
					(thickness 0.15)
				)
				(justify right)
			)
		)
		(property "Tolerance" "1%"
			(at 226.06 69.85 0)
			(effects
				(font
					(size 1.27 1.27)
				)
				(justify left bottom)
				(hide yes)
			)
		)
		(pin "2"
		)
		(pin "1"
		)
		(instances
			(project "data-center-rdimm-ddr5-tester"
				(path ""
					(reference "R244")
					(unit 1)
				)
			)
		)
	)
	(symbol
		(lib_id "antmicropower:GND")
		(at 364.49 240.03 0)
		(unit 1)
		(exclude_from_sim no)
		(in_bom yes)
		(on_board yes)
		(dnp no)
		(fields_autoplaced yes)
		(property "Reference" "#PWR047"
			(at 364.49 246.38 0)
			(effects
				(font
					(size 1.27 1.27)
				)
				(hide yes)
			)
		)
		(property "Value" "GND"
			(at 362.585 244.475 0)
			(effects
				(font
					(size 1.27 1.27)
					(thickness 0.15)
				)
				(justify left bottom)
			)
		)
		(property "Footprint" ""
			(at 373.38 247.65 0)
			(effects
				(font
					(size 1.27 1.27)
					(thickness 0.15)
				)
				(justify left bottom)
				(hide yes)
			)
		)
		(property "Datasheet" ""
			(at 373.38 252.73 0)
			(effects
				(font
					(size 1.27 1.27)
					(thickness 0.15)
				)
				(justify left bottom)
				(hide yes)
			)
		)
		(property "Description" ""
			(at 364.49 240.03 0)
			(effects
				(font
					(size 1.27 1.27)
				)
				(hide yes)
			)
		)
		(property "Author" "Antmicro"
			(at 373.38 245.11 0)
			(effects
				(font
					(size 1.27 1.27)
					(thickness 0.15)
				)
				(justify left bottom)
				(hide yes)
			)
		)
		(property "License" "Apache-2.0"
			(at 373.38 247.65 0)
			(effects
				(font
					(size 1.27 1.27)
					(thickness 0.15)
				)
				(justify left bottom)
				(hide yes)
			)
		)
		(pin "1"
		)
		(instances
			(project "data-center-rdimm-ddr5-tester"
				(path ""
					(reference "#PWR047")
					(unit 1)
				)
			)
		)
	)
	(symbol
		(lib_id "antmicropower:GND")
		(at 281.94 116.84 0)
		(unit 1)
		(exclude_from_sim no)
		(in_bom yes)
		(on_board yes)
		(dnp no)
		(fields_autoplaced yes)
		(property "Reference" "#PWR0537"
			(at 281.94 123.19 0)
			(effects
				(font
					(size 1.27 1.27)
				)
				(hide yes)
			)
		)
		(property "Value" "GND"
			(at 280.035 121.285 0)
			(effects
				(font
					(size 1.27 1.27)
					(thickness 0.15)
				)
				(justify left bottom)
			)
		)
		(property "Footprint" ""
			(at 290.83 124.46 0)
			(effects
				(font
					(size 1.27 1.27)
					(thickness 0.15)
				)
				(justify left bottom)
				(hide yes)
			)
		)
		(property "Datasheet" ""
			(at 290.83 129.54 0)
			(effects
				(font
					(size 1.27 1.27)
					(thickness 0.15)
				)
				(justify left bottom)
				(hide yes)
			)
		)
		(property "Description" ""
			(at 281.94 116.84 0)
			(effects
				(font
					(size 1.27 1.27)
				)
				(hide yes)
			)
		)
		(property "Author" "Antmicro"
			(at 290.83 121.92 0)
			(effects
				(font
					(size 1.27 1.27)
					(thickness 0.15)
				)
				(justify left bottom)
				(hide yes)
			)
		)
		(property "License" "Apache-2.0"
			(at 290.83 124.46 0)
			(effects
				(font
					(size 1.27 1.27)
					(thickness 0.15)
				)
				(justify left bottom)
				(hide yes)
			)
		)
		(pin "1"
		)
		(instances
			(project "data-center-rdimm-ddr5-tester"
				(path ""
					(reference "#PWR0537")
					(unit 1)
				)
			)
		)
	)
	(symbol
		(lib_id "antmicropower:GND")
		(at 354.33 240.03 0)
		(unit 1)
		(exclude_from_sim no)
		(in_bom yes)
		(on_board yes)
		(dnp no)
		(fields_autoplaced yes)
		(property "Reference" "#PWR045"
			(at 354.33 246.38 0)
			(effects
				(font
					(size 1.27 1.27)
				)
				(hide yes)
			)
		)
		(property "Value" "GND"
			(at 352.425 244.475 0)
			(effects
				(font
					(size 1.27 1.27)
					(thickness 0.15)
				)
				(justify left bottom)
			)
		)
		(property "Footprint" ""
			(at 363.22 247.65 0)
			(effects
				(font
					(size 1.27 1.27)
					(thickness 0.15)
				)
				(justify left bottom)
				(hide yes)
			)
		)
		(property "Datasheet" ""
			(at 363.22 252.73 0)
			(effects
				(font
					(size 1.27 1.27)
					(thickness 0.15)
				)
				(justify left bottom)
				(hide yes)
			)
		)
		(property "Description" ""
			(at 354.33 240.03 0)
			(effects
				(font
					(size 1.27 1.27)
				)
				(hide yes)
			)
		)
		(property "Author" "Antmicro"
			(at 363.22 245.11 0)
			(effects
				(font
					(size 1.27 1.27)
					(thickness 0.15)
				)
				(justify left bottom)
				(hide yes)
			)
		)
		(property "License" "Apache-2.0"
			(at 363.22 247.65 0)
			(effects
				(font
					(size 1.27 1.27)
					(thickness 0.15)
				)
				(justify left bottom)
				(hide yes)
			)
		)
		(pin "1"
		)
		(instances
			(project "data-center-rdimm-ddr5-tester"
				(path ""
					(reference "#PWR045")
					(unit 1)
				)
			)
		)
	)
	(symbol
		(lib_id "antmicropower:GND")
		(at 248.92 97.79 0)
		(unit 1)
		(exclude_from_sim no)
		(in_bom yes)
		(on_board yes)
		(dnp no)
		(fields_autoplaced yes)
		(property "Reference" "#PWR0540"
			(at 248.92 104.14 0)
			(effects
				(font
					(size 1.27 1.27)
				)
				(hide yes)
			)
		)
		(property "Value" "GND"
			(at 247.015 102.235 0)
			(effects
				(font
					(size 1.27 1.27)
					(thickness 0.15)
				)
				(justify left bottom)
			)
		)
		(property "Footprint" ""
			(at 257.81 105.41 0)
			(effects
				(font
					(size 1.27 1.27)
					(thickness 0.15)
				)
				(justify left bottom)
				(hide yes)
			)
		)
		(property "Datasheet" ""
			(at 257.81 110.49 0)
			(effects
				(font
					(size 1.27 1.27)
					(thickness 0.15)
				)
				(justify left bottom)
				(hide yes)
			)
		)
		(property "Description" ""
			(at 248.92 97.79 0)
			(effects
				(font
					(size 1.27 1.27)
				)
				(hide yes)
			)
		)
		(property "Author" "Antmicro"
			(at 257.81 102.87 0)
			(effects
				(font
					(size 1.27 1.27)
					(thickness 0.15)
				)
				(justify left bottom)
				(hide yes)
			)
		)
		(property "License" "Apache-2.0"
			(at 257.81 105.41 0)
			(effects
				(font
					(size 1.27 1.27)
					(thickness 0.15)
				)
				(justify left bottom)
				(hide yes)
			)
		)
		(pin "1"
		)
		(instances
			(project "data-center-rdimm-ddr5-tester"
				(path ""
					(reference "#PWR0540")
					(unit 1)
				)
			)
		)
	)
	(symbol
		(lib_id "antmicroResistors0402:R_4k7_0402")
		(at 347.98 161.29 270)
		(unit 1)
		(exclude_from_sim no)
		(in_bom yes)
		(on_board yes)
		(dnp no)
		(fields_autoplaced yes)
		(property "Reference" "R78"
			(at 346.075 162.56 90)
			(effects
				(font
					(size 1.27 1.27)
				)
				(justify right)
			)
		)
		(property "Value" "R_4k7_0402"
			(at 335.28 181.61 0)
			(effects
				(font
					(size 1.27 1.27)
					(thickness 0.15)
				)
				(justify left bottom)
				(hide yes)
			)
		)
		(property "Footprint" "antmicro-footprints:R_0402_1005Metric"
			(at 332.74 181.61 0)
			(effects
				(font
					(size 1.27 1.27)
					(thickness 0.15)
				)
				(justify left bottom)
				(hide yes)
			)
		)
		(property "Datasheet" "https://www.bourns.com/docs/product-datasheets/cr.pdf"
			(at 330.2 181.61 0)
			(effects
				(font
					(size 1.27 1.27)
					(thickness 0.15)
				)
				(justify left bottom)
				(hide yes)
			)
		)
		(property "Description" ""
			(at 347.98 161.29 0)
			(effects
				(font
					(size 1.27 1.27)
				)
				(hide yes)
			)
		)
		(property "Manufacturer" "Bourns"
			(at 325.12 181.61 0)
			(effects
				(font
					(size 1.27 1.27)
					(thickness 0.15)
				)
				(justify left bottom)
				(hide yes)
			)
		)
		(property "MPN" "CR0402-FX-4701GLF"
			(at 327.66 181.61 0)
			(effects
				(font
					(size 1.27 1.27)
					(thickness 0.15)
				)
				(justify left bottom)
				(hide yes)
			)
		)
		(property "Val" "4k7"
			(at 346.075 165.7349 90)
			(effects
				(font
					(size 1.27 1.27)
					(thickness 0.15)
				)
				(justify right)
			)
		)
		(property "License" "Apache-2.0"
			(at 322.58 181.61 0)
			(effects
				(font
					(size 1.27 1.27)
					(thickness 0.15)
				)
				(justify left bottom)
				(hide yes)
			)
		)
		(property "Author" "Antmicro"
			(at 320.04 181.61 0)
			(effects
				(font
					(size 1.27 1.27)
					(thickness 0.15)
				)
				(justify left bottom)
				(hide yes)
			)
		)
		(property "Tolerance" "1%"
			(at 337.82 181.61 0)
			(effects
				(font
					(size 1.27 1.27)
				)
				(justify left bottom)
				(hide yes)
			)
		)
		(pin "1"
		)
		(pin "2"
		)
		(instances
			(project "data-center-rdimm-ddr5-tester"
				(path ""
					(reference "R78")
					(unit 1)
				)
			)
		)
	)
	(symbol
		(lib_id "antmicroTransistorsFETsMOSFETsSingle:BSS138PW")
		(at 243.84 196.85 0)
		(unit 1)
		(exclude_from_sim no)
		(in_bom yes)
		(on_board yes)
		(dnp no)
		(fields_autoplaced yes)
		(property "Reference" "Q9"
			(at 255.27 193.04 0)
			(effects
				(font
					(size 1.27 1.27)
				)
				(justify left)
			)
		)
		(property "Value" "BSS138PW"
			(at 255.27 196.2149 0)
			(effects
				(font
					(size 1.27 1.27)
					(thickness 0.15)
				)
				(justify left)
			)
		)
		(property "Footprint" "antmicro-footprints:SC70-3"
			(at 266.7 208.28 0)
			(effects
				(font
					(size 1.27 1.27)
					(thickness 0.15)
				)
				(justify left bottom)
				(hide yes)
			)
		)
		(property "Datasheet" "https://assets.nexperia.com/documents/data-sheet/BSS138PW.pdf"
			(at 266.7 210.82 0)
			(effects
				(font
					(size 1.27 1.27)
					(thickness 0.15)
				)
				(justify left bottom)
				(hide yes)
			)
		)
		(property "Description" ""
			(at 243.84 196.85 0)
			(effects
				(font
					(size 1.27 1.27)
				)
				(hide yes)
			)
		)
		(property "MPN" "BSS138PW"
			(at 266.7 213.36 0)
			(effects
				(font
					(size 1.27 1.27)
					(thickness 0.15)
				)
				(justify left bottom)
				(hide yes)
			)
		)
		(property "Manufacturer" "Nexperia"
			(at 266.7 215.9 0)
			(effects
				(font
					(size 1.27 1.27)
					(thickness 0.15)
				)
				(justify left bottom)
				(hide yes)
			)
		)
		(property "Author" "Antmicro"
			(at 266.7 218.44 0)
			(effects
				(font
					(size 1.27 1.27)
					(thickness 0.15)
				)
				(justify left bottom)
				(hide yes)
			)
		)
		(property "License" "Apache-2.0"
			(at 266.7 220.98 0)
			(effects
				(font
					(size 1.27 1.27)
					(thickness 0.15)
				)
				(justify left bottom)
				(hide yes)
			)
		)
		(pin "1"
		)
		(pin "2"
		)
		(pin "3"
		)
		(instances
			(project "data-center-rdimm-ddr5-tester"
				(path ""
					(reference "Q9")
					(unit 1)
				)
			)
		)
	)
	(symbol
		(lib_id "antmicropower:PWR_FLAG")
		(at 248.92 81.28 0)
		(unit 1)
		(exclude_from_sim no)
		(in_bom yes)
		(on_board yes)
		(dnp no)
		(fields_autoplaced yes)
		(property "Reference" "#FLG022"
			(at 248.92 79.375 0)
			(effects
				(font
					(size 1.27 1.27)
				)
				(hide yes)
			)
		)
		(property "Value" "PWR_FLAG"
			(at 248.92 77.7042 0)
			(effects
				(font
					(size 1.27 1.27)
				)
			)
		)
		(property "Footprint" ""
			(at 248.92 81.28 0)
			(effects
				(font
					(size 1.27 1.27)
				)
				(hide yes)
			)
		)
		(property "Datasheet" ""
			(at 248.92 81.28 0)
			(effects
				(font
					(size 1.27 1.27)
				)
				(hide yes)
			)
		)
		(property "Description" ""
			(at 248.92 81.28 0)
			(effects
				(font
					(size 1.27 1.27)
				)
				(hide yes)
			)
		)
		(pin "1"
		)
		(instances
			(project "data-center-rdimm-ddr5-tester"
				(path ""
					(reference "#FLG022")
					(unit 1)
				)
			)
		)
	)
	(symbol
		(lib_id "antmicropower:GND")
		(at 226.06 62.23 0)
		(unit 1)
		(exclude_from_sim no)
		(in_bom yes)
		(on_board yes)
		(dnp no)
		(fields_autoplaced yes)
		(property "Reference" "#PWR0536"
			(at 226.06 68.58 0)
			(effects
				(font
					(size 1.27 1.27)
				)
				(hide yes)
			)
		)
		(property "Value" "GND"
			(at 224.155 66.675 0)
			(effects
				(font
					(size 1.27 1.27)
					(thickness 0.15)
				)
				(justify left bottom)
			)
		)
		(property "Footprint" ""
			(at 234.95 69.85 0)
			(effects
				(font
					(size 1.27 1.27)
					(thickness 0.15)
				)
				(justify left bottom)
				(hide yes)
			)
		)
		(property "Datasheet" ""
			(at 234.95 74.93 0)
			(effects
				(font
					(size 1.27 1.27)
					(thickness 0.15)
				)
				(justify left bottom)
				(hide yes)
			)
		)
		(property "Description" ""
			(at 226.06 62.23 0)
			(effects
				(font
					(size 1.27 1.27)
				)
				(hide yes)
			)
		)
		(property "Author" "Antmicro"
			(at 234.95 67.31 0)
			(effects
				(font
					(size 1.27 1.27)
					(thickness 0.15)
				)
				(justify left bottom)
				(hide yes)
			)
		)
		(property "License" "Apache-2.0"
			(at 234.95 69.85 0)
			(effects
				(font
					(size 1.27 1.27)
					(thickness 0.15)
				)
				(justify left bottom)
				(hide yes)
			)
		)
		(pin "1"
		)
		(instances
			(project "data-center-rdimm-ddr5-tester"
				(path ""
					(reference "#PWR0536")
					(unit 1)
				)
			)
		)
	)
	(symbol
		(lib_id "antmicroResistors0402:R_10k_0402")
		(at 243.84 270.51 90)
		(unit 1)
		(exclude_from_sim no)
		(in_bom yes)
		(on_board yes)
		(dnp no)
		(fields_autoplaced yes)
		(property "Reference" "R128"
			(at 245.491 267.1394 90)
			(effects
				(font
					(size 1.27 1.27)
					(thickness 0.15)
				)
				(justify right)
			)
		)
		(property "Value" "R_10k_0402"
			(at 256.54 250.19 0)
			(effects
				(font
					(size 1.27 1.27)
					(thickness 0.15)
				)
				(justify left bottom)
				(hide yes)
			)
		)
		(property "Footprint" "antmicro-footprints:R_0402_1005Metric"
			(at 259.08 250.19 0)
			(effects
				(font
					(size 1.27 1.27)
					(thickness 0.15)
				)
				(justify left bottom)
				(hide yes)
			)
		)
		(property "Datasheet" "https://www.bourns.com/docs/product-datasheets/cr.pdf"
			(at 261.62 250.19 0)
			(effects
				(font
					(size 1.27 1.27)
					(thickness 0.15)
				)
				(justify left bottom)
				(hide yes)
			)
		)
		(property "Description" ""
			(at 243.84 270.51 0)
			(effects
				(font
					(size 1.27 1.27)
				)
				(hide yes)
			)
		)
		(property "MPN" "CR0402-FX-1002GLF"
			(at 264.16 250.19 0)
			(effects
				(font
					(size 1.27 1.27)
					(thickness 0.15)
				)
				(justify left bottom)
				(hide yes)
			)
		)
		(property "Manufacturer" "Bourns"
			(at 266.7 250.19 0)
			(effects
				(font
					(size 1.27 1.27)
					(thickness 0.15)
				)
				(justify left bottom)
				(hide yes)
			)
		)
		(property "License" "Apache-2.0"
			(at 269.24 250.19 0)
			(effects
				(font
					(size 1.27 1.27)
					(thickness 0.15)
				)
				(justify left bottom)
				(hide yes)
			)
		)
		(property "Author" "Antmicro"
			(at 271.78 250.19 0)
			(effects
				(font
					(size 1.27 1.27)
					(thickness 0.15)
				)
				(justify left bottom)
				(hide yes)
			)
		)
		(property "Val" "10k"
			(at 245.491 269.6631 90)
			(effects
				(font
					(size 1.27 1.27)
					(thickness 0.15)
				)
				(justify right)
			)
		)
		(property "Tolerance" "1%"
			(at 254 250.19 0)
			(effects
				(font
					(size 1.27 1.27)
				)
				(justify left bottom)
				(hide yes)
			)
		)
		(pin "1"
		)
		(pin "2"
		)
		(instances
			(project "data-center-rdimm-ddr5-tester"
				(path ""
					(reference "R128")
					(unit 1)
				)
			)
		)
	)
	(symbol
		(lib_id "antmicropower:VDC")
		(at 214.63 31.75 0)
		(unit 1)
		(exclude_from_sim no)
		(in_bom yes)
		(on_board yes)
		(dnp no)
		(fields_autoplaced yes)
		(property "Reference" "#PWR0533"
			(at 214.63 34.29 0)
			(effects
				(font
					(size 1.27 1.27)
				)
				(hide yes)
			)
		)
		(property "Value" "VDC"
			(at 214.63 27.305 0)
			(effects
				(font
					(size 1.27 1.27)
				)
			)
		)
		(property "Footprint" ""
			(at 214.63 31.75 0)
			(effects
				(font
					(size 1.27 1.27)
				)
				(hide yes)
			)
		)
		(property "Datasheet" ""
			(at 214.63 31.75 0)
			(effects
				(font
					(size 1.27 1.27)
				)
				(hide yes)
			)
		)
		(property "Description" ""
			(at 214.63 31.75 0)
			(effects
				(font
					(size 1.27 1.27)
				)
				(hide yes)
			)
		)
		(pin "1"
		)
		(instances
			(project "data-center-rdimm-ddr5-tester"
				(path ""
					(reference "#PWR0533")
					(unit 1)
				)
			)
		)
	)
	(symbol
		(lib_id "antmicropower:VDD")
		(at 354.33 232.41 0)
		(unit 1)
		(exclude_from_sim no)
		(in_bom yes)
		(on_board yes)
		(dnp no)
		(fields_autoplaced yes)
		(property "Reference" "#PWR046"
			(at 354.33 236.22 0)
			(effects
				(font
					(size 1.27 1.27)
				)
				(hide yes)
			)
		)
		(property "Value" "VDDQ"
			(at 354.33 227.33 0)
			(effects
				(font
					(size 1.27 1.27)
				)
			)
		)
		(property "Footprint" ""
			(at 354.33 232.41 0)
			(effects
				(font
					(size 1.27 1.27)
				)
				(hide yes)
			)
		)
		(property "Datasheet" ""
			(at 354.33 232.41 0)
			(effects
				(font
					(size 1.27 1.27)
				)
				(hide yes)
			)
		)
		(property "Description" ""
			(at 354.33 232.41 0)
			(effects
				(font
					(size 1.27 1.27)
				)
				(hide yes)
			)
		)
		(pin "1"
		)
		(instances
			(project "data-center-rdimm-ddr5-tester"
				(path ""
					(reference "#PWR046")
					(unit 1)
				)
			)
		)
	)
	(symbol
		(lib_id "antmicroPushbuttonSwitches:SW_KMR211NGLFS_SMD")
		(at 345.44 180.34 90)
		(unit 1)
		(exclude_from_sim no)
		(in_bom yes)
		(on_board yes)
		(dnp no)
		(property "Reference" "SW3"
			(at 328.295 176.53 90)
			(effects
				(font
					(size 1.27 1.27)
					(thickness 0.15)
				)
				(justify right)
			)
		)
		(property "Value" "SW_KMR211NGLFS_SMD"
			(at 353.06 154.94 0)
			(effects
				(font
					(size 1.27 1.27)
					(thickness 0.15)
				)
				(justify left bottom)
				(hide yes)
			)
		)
		(property "Footprint" "antmicro-footprints:SW_KMR211NGLFS_SMD"
			(at 355.6 154.94 0)
			(effects
				(font
					(size 1.27 1.27)
					(thickness 0.15)
				)
				(justify left bottom)
				(hide yes)
			)
		)
		(property "Datasheet" "http://www.farnell.com/datasheets/2631211.pdf"
			(at 358.14 154.94 0)
			(effects
				(font
					(size 1.27 1.27)
					(thickness 0.15)
				)
				(justify left bottom)
				(hide yes)
			)
		)
		(property "Description" ""
			(at 345.44 180.34 0)
			(effects
				(font
					(size 1.27 1.27)
				)
				(hide yes)
			)
		)
		(property "MPN" "KMR211NGLFS"
			(at 328.295 179.07 90)
			(effects
				(font
					(size 1.27 1.27)
					(thickness 0.15)
				)
				(justify right)
			)
		)
		(property "Manufacturer" "C&K"
			(at 360.68 154.94 0)
			(effects
				(font
					(size 1.27 1.27)
					(thickness 0.15)
				)
				(justify left bottom)
				(hide yes)
			)
		)
		(property "Author" "Antmicro"
			(at 363.22 154.94 0)
			(effects
				(font
					(size 1.27 1.27)
					(thickness 0.15)
				)
				(justify left bottom)
				(hide yes)
			)
		)
		(property "License" "Apache-2.0"
			(at 365.76 154.94 0)
			(effects
				(font
					(size 1.27 1.27)
					(thickness 0.15)
				)
				(justify left bottom)
				(hide yes)
			)
		)
		(pin "1"
		)
		(pin "2"
		)
		(pin "3"
		)
		(pin "4"
		)
		(instances
			(project "data-center-rdimm-ddr5-tester"
				(path ""
					(reference "SW3")
					(unit 1)
				)
			)
		)
	)
	(symbol
		(lib_id "antmicroTransistorsFETsMOSFETsSingle:BSS138PW")
		(at 280.67 176.53 0)
		(unit 1)
		(exclude_from_sim no)
		(in_bom yes)
		(on_board yes)
		(dnp no)
		(property "Reference" "Q11"
			(at 292.1 172.72 0)
			(effects
				(font
					(size 1.27 1.27)
				)
				(justify left)
			)
		)
		(property "Value" "BSS138PW"
			(at 292.1 175.8949 0)
			(effects
				(font
					(size 1.27 1.27)
					(thickness 0.15)
				)
				(justify left)
			)
		)
		(property "Footprint" "antmicro-footprints:SC70-3"
			(at 303.53 187.96 0)
			(effects
				(font
					(size 1.27 1.27)
					(thickness 0.15)
				)
				(justify left bottom)
				(hide yes)
			)
		)
		(property "Datasheet" "https://assets.nexperia.com/documents/data-sheet/BSS138PW.pdf"
			(at 303.53 190.5 0)
			(effects
				(font
					(size 1.27 1.27)
					(thickness 0.15)
				)
				(justify left bottom)
				(hide yes)
			)
		)
		(property "Description" ""
			(at 280.67 176.53 0)
			(effects
				(font
					(size 1.27 1.27)
				)
				(hide yes)
			)
		)
		(property "MPN" "BSS138PW"
			(at 303.53 193.04 0)
			(effects
				(font
					(size 1.27 1.27)
					(thickness 0.15)
				)
				(justify left bottom)
				(hide yes)
			)
		)
		(property "Manufacturer" "Nexperia"
			(at 303.53 195.58 0)
			(effects
				(font
					(size 1.27 1.27)
					(thickness 0.15)
				)
				(justify left bottom)
				(hide yes)
			)
		)
		(property "Author" "Antmicro"
			(at 303.53 198.12 0)
			(effects
				(font
					(size 1.27 1.27)
					(thickness 0.15)
				)
				(justify left bottom)
				(hide yes)
			)
		)
		(property "License" "Apache-2.0"
			(at 303.53 200.66 0)
			(effects
				(font
					(size 1.27 1.27)
					(thickness 0.15)
				)
				(justify left bottom)
				(hide yes)
			)
		)
		(pin "1"
		)
		(pin "2"
		)
		(pin "3"
		)
		(instances
			(project "data-center-rdimm-ddr5-tester"
				(path ""
					(reference "Q11")
					(unit 1)
				)
			)
		)
	)
	(symbol
		(lib_id "antmicropower:PWR_FLAG")
		(at 248.92 31.75 0)
		(unit 1)
		(exclude_from_sim no)
		(in_bom yes)
		(on_board yes)
		(dnp no)
		(fields_autoplaced yes)
		(property "Reference" "#FLG021"
			(at 248.92 29.845 0)
			(effects
				(font
					(size 1.27 1.27)
				)
				(hide yes)
			)
		)
		(property "Value" "PWR_FLAG"
			(at 248.92 28.1742 0)
			(effects
				(font
					(size 1.27 1.27)
				)
			)
		)
		(property "Footprint" ""
			(at 248.92 31.75 0)
			(effects
				(font
					(size 1.27 1.27)
				)
				(hide yes)
			)
		)
		(property "Datasheet" ""
			(at 248.92 31.75 0)
			(effects
				(font
					(size 1.27 1.27)
				)
				(hide yes)
			)
		)
		(property "Description" ""
			(at 248.92 31.75 0)
			(effects
				(font
					(size 1.27 1.27)
				)
				(hide yes)
			)
		)
		(pin "1"
		)
		(instances
			(project "data-center-rdimm-ddr5-tester"
				(path ""
					(reference "#FLG021")
					(unit 1)
				)
			)
		)
	)
	(symbol
		(lib_id "antmicroTransistorsFETsMOSFETsSingle:SI7613DN-T1-GE3")
		(at 226.06 40.64 270)
		(mirror x)
		(unit 1)
		(exclude_from_sim no)
		(in_bom yes)
		(on_board yes)
		(dnp no)
		(property "Reference" "Q23"
			(at 228.6 26.67 90)
			(effects
				(font
					(size 1.27 1.27)
					(thickness 0.15)
				)
			)
		)
		(property "Value" "SI7613DN-T1-GE3"
			(at 228.6 25.4 0)
			(effects
				(font
					(size 1.27 1.27)
					(thickness 0.15)
				)
				(justify left bottom)
				(hide yes)
			)
		)
		(property "Footprint" "antmicro-footprints:Vishay_PowerPAK_1212-8_Single"
			(at 227.33 25.4 0)
			(effects
				(font
					(size 1.27 1.27)
					(thickness 0.15)
				)
				(justify left bottom)
				(hide yes)
			)
		)
		(property "Datasheet" "https://www.vishay.com/docs/64809/si7613dn.pdf"
			(at 224.79 25.4 0)
			(effects
				(font
					(size 1.27 1.27)
					(thickness 0.15)
				)
				(justify left bottom)
				(hide yes)
			)
		)
		(property "Description" ""
			(at 226.06 40.64 0)
			(effects
				(font
					(size 1.27 1.27)
				)
				(hide yes)
			)
		)
		(property "MPN" "SI7613DN-T1-GE3"
			(at 228.6 29.21 90)
			(effects
				(font
					(size 1.27 1.27)
					(thickness 0.15)
				)
			)
		)
		(property "Manufacturer" "Vishay"
			(at 218.44 25.4 0)
			(effects
				(font
					(size 1.27 1.27)
					(thickness 0.15)
				)
				(justify left bottom)
				(hide yes)
			)
		)
		(property "Author" "Antmicro"
			(at 215.9 25.4 0)
			(effects
				(font
					(size 1.27 1.27)
					(thickness 0.15)
				)
				(justify left bottom)
				(hide yes)
			)
		)
		(property "License" "Apache-2.0"
			(at 213.36 25.4 0)
			(effects
				(font
					(size 1.27 1.27)
					(thickness 0.15)
				)
				(justify left bottom)
				(hide yes)
			)
		)
		(pin "4"
		)
		(pin "5"
		)
		(pin "3"
		)
		(pin "2"
		)
		(pin "1"
		)
		(instances
			(project "data-center-rdimm-ddr5-tester"
				(path ""
					(reference "Q23")
					(unit 1)
				)
			)
		)
	)
	(symbol
		(lib_id "antmicropower:GND")
		(at 243.84 271.78 0)
		(mirror y)
		(unit 1)
		(exclude_from_sim no)
		(in_bom yes)
		(on_board yes)
		(dnp no)
		(fields_autoplaced yes)
		(property "Reference" "#PWR0275"
			(at 243.84 278.13 0)
			(effects
				(font
					(size 1.27 1.27)
				)
				(hide yes)
			)
		)
		(property "Value" "GND"
			(at 245.745 276.225 0)
			(effects
				(font
					(size 1.27 1.27)
					(thickness 0.15)
				)
				(justify left bottom)
			)
		)
		(property "Footprint" ""
			(at 234.95 279.4 0)
			(effects
				(font
					(size 1.27 1.27)
					(thickness 0.15)
				)
				(justify left bottom)
				(hide yes)
			)
		)
		(property "Datasheet" ""
			(at 234.95 284.48 0)
			(effects
				(font
					(size 1.27 1.27)
					(thickness 0.15)
				)
				(justify left bottom)
				(hide yes)
			)
		)
		(property "Description" ""
			(at 243.84 271.78 0)
			(effects
				(font
					(size 1.27 1.27)
				)
				(hide yes)
			)
		)
		(property "Author" "Antmicro"
			(at 234.95 276.86 0)
			(effects
				(font
					(size 1.27 1.27)
					(thickness 0.15)
				)
				(justify left bottom)
				(hide yes)
			)
		)
		(property "License" "Apache-2.0"
			(at 234.95 279.4 0)
			(effects
				(font
					(size 1.27 1.27)
					(thickness 0.15)
				)
				(justify left bottom)
				(hide yes)
			)
		)
		(pin "1"
		)
		(instances
			(project "data-center-rdimm-ddr5-tester"
				(path ""
					(reference "#PWR0275")
					(unit 1)
				)
			)
		)
	)
	(symbol
		(lib_id "antmicroCapacitors0402:C_100n_0402")
		(at 354.33 238.76 90)
		(unit 1)
		(exclude_from_sim no)
		(in_bom yes)
		(on_board yes)
		(dnp no)
		(fields_autoplaced yes)
		(property "Reference" "C8"
			(at 356.6541 235.383 90)
			(effects
				(font
					(size 1.27 1.27)
					(thickness 0.15)
				)
				(justify right)
			)
		)
		(property "Value" "C_100n_0402"
			(at 364.49 218.44 0)
			(effects
				(font
					(size 1.27 1.27)
					(thickness 0.15)
				)
				(justify left bottom)
				(hide yes)
			)
		)
		(property "Footprint" "antmicro-footprints:C_0402_1005Metric"
			(at 367.03 218.44 0)
			(effects
				(font
					(size 1.27 1.27)
					(thickness 0.15)
				)
				(justify left bottom)
				(hide yes)
			)
		)
		(property "Datasheet" "https://www.murata.com/products/productdetail?partno=GRM155R61H104KE14%23"
			(at 369.57 218.44 0)
			(effects
				(font
					(size 1.27 1.27)
					(thickness 0.15)
				)
				(justify left bottom)
				(hide yes)
			)
		)
		(property "Description" ""
			(at 354.33 238.76 0)
			(effects
				(font
					(size 1.27 1.27)
				)
				(hide yes)
			)
		)
		(property "MPN" "GRM155R61H104KE14D"
			(at 372.11 218.44 0)
			(effects
				(font
					(size 1.27 1.27)
					(thickness 0.15)
				)
				(justify left bottom)
				(hide yes)
			)
		)
		(property "Manufacturer" "Murata"
			(at 374.65 218.44 0)
			(effects
				(font
					(size 1.27 1.27)
					(thickness 0.15)
				)
				(justify left bottom)
				(hide yes)
			)
		)
		(property "License" "Apache-2.0"
			(at 377.19 218.44 0)
			(effects
				(font
					(size 1.27 1.27)
					(thickness 0.15)
				)
				(justify left bottom)
				(hide yes)
			)
		)
		(property "Author" "Antmicro"
			(at 379.73 218.44 0)
			(effects
				(font
					(size 1.27 1.27)
					(thickness 0.15)
				)
				(justify left bottom)
				(hide yes)
			)
		)
		(property "Val" "100n"
			(at 356.6541 237.9067 90)
			(effects
				(font
					(size 1.27 1.27)
					(thickness 0.15)
				)
				(justify right)
			)
		)
		(property "Voltage" "50V"
			(at 382.27 218.44 0)
			(effects
				(font
					(size 1.27 1.27)
				)
				(justify left bottom)
				(hide yes)
			)
		)
		(property "Dielectric" "X5R"
			(at 384.81 218.44 0)
			(effects
				(font
					(size 1.27 1.27)
				)
				(justify left bottom)
				(hide yes)
			)
		)
		(pin "1"
		)
		(pin "2"
		)
		(instances
			(project "data-center-rdimm-ddr5-tester"
				(path ""
					(reference "C8")
					(unit 1)
				)
			)
		)
	)
	(symbol
		(lib_id "antmicropower:GND")
		(at 281.94 100.33 0)
		(unit 1)
		(exclude_from_sim no)
		(in_bom yes)
		(on_board yes)
		(dnp no)
		(fields_autoplaced yes)
		(property "Reference" "#PWR037"
			(at 281.94 106.68 0)
			(effects
				(font
					(size 1.27 1.27)
				)
				(hide yes)
			)
		)
		(property "Value" "GND"
			(at 280.035 104.775 0)
			(effects
				(font
					(size 1.27 1.27)
					(thickness 0.15)
				)
				(justify left bottom)
			)
		)
		(property "Footprint" ""
			(at 290.83 107.95 0)
			(effects
				(font
					(size 1.27 1.27)
					(thickness 0.15)
				)
				(justify left bottom)
				(hide yes)
			)
		)
		(property "Datasheet" ""
			(at 290.83 113.03 0)
			(effects
				(font
					(size 1.27 1.27)
					(thickness 0.15)
				)
				(justify left bottom)
				(hide yes)
			)
		)
		(property "Description" ""
			(at 281.94 100.33 0)
			(effects
				(font
					(size 1.27 1.27)
				)
				(hide yes)
			)
		)
		(property "Author" "Antmicro"
			(at 290.83 105.41 0)
			(effects
				(font
					(size 1.27 1.27)
					(thickness 0.15)
				)
				(justify left bottom)
				(hide yes)
			)
		)
		(property "License" "Apache-2.0"
			(at 290.83 107.95 0)
			(effects
				(font
					(size 1.27 1.27)
					(thickness 0.15)
				)
				(justify left bottom)
				(hide yes)
			)
		)
		(pin "1"
		)
		(instances
			(project "data-center-rdimm-ddr5-tester"
				(path ""
					(reference "#PWR037")
					(unit 1)
				)
			)
		)
	)
	(symbol
		(lib_id "antmicropower:+3V3")
		(at 214.63 82.55 0)
		(unit 1)
		(exclude_from_sim no)
		(in_bom yes)
		(on_board yes)
		(dnp no)
		(fields_autoplaced yes)
		(property "Reference" "#PWR0538"
			(at 229.87 82.55 0)
			(effects
				(font
					(size 1.27 1.27)
					(thickness 0.15)
				)
				(justify left bottom)
				(hide yes)
			)
		)
		(property "Value" "+3V3"
			(at 214.63 78.74 0)
			(effects
				(font
					(size 1.27 1.27)
					(thickness 0.15)
				)
			)
		)
		(property "Footprint" ""
			(at 229.87 90.17 0)
			(effects
				(font
					(size 1.27 1.27)
					(thickness 0.15)
				)
				(justify left bottom)
				(hide yes)
			)
		)
		(property "Datasheet" ""
			(at 229.87 92.71 0)
			(effects
				(font
					(size 1.27 1.27)
					(thickness 0.15)
				)
				(justify left bottom)
				(hide yes)
			)
		)
		(property "Description" ""
			(at 214.63 82.55 0)
			(effects
				(font
					(size 1.27 1.27)
				)
				(hide yes)
			)
		)
		(property "Author" "Antmicro"
			(at 229.87 85.09 0)
			(effects
				(font
					(size 1.27 1.27)
					(thickness 0.15)
				)
				(justify left bottom)
				(hide yes)
			)
		)
		(property "License" "Apache-2.0"
			(at 229.87 87.63 0)
			(effects
				(font
					(size 1.27 1.27)
					(thickness 0.15)
				)
				(justify left bottom)
				(hide yes)
			)
		)
		(pin "1"
		)
		(instances
			(project "data-center-rdimm-ddr5-tester"
				(path ""
					(reference "#PWR0538")
					(unit 1)
				)
			)
		)
	)
	(symbol
		(lib_name "LED_RGY_0606_APTF1616SURKCGKSYKC_1")
		(lib_id "antmicroLEDIndicationDiscrete:LED_RGY_0606_APTF1616SURKCGKSYKC")
		(at 226.06 154.94 0)
		(unit 1)
		(exclude_from_sim no)
		(in_bom yes)
		(on_board yes)
		(dnp no)
		(fields_autoplaced yes)
		(property "Reference" "D20"
			(at 235.585 139.7 0)
			(effects
				(font
					(size 1.27 1.27)
					(thickness 0.15)
				)
			)
		)
		(property "Value" "LED_RGY_0606_APTF1616SURKCGKSYKC"
			(at 256.54 162.56 0)
			(effects
				(font
					(size 1.27 1.27)
					(thickness 0.15)
				)
				(justify left bottom)
				(hide yes)
			)
		)
		(property "Footprint" "antmicro-footprints:LED_RGY_1.6x1.6mm_APTF1616"
			(at 256.54 165.1 0)
			(effects
				(font
					(size 1.27 1.27)
					(thickness 0.15)
				)
				(justify left bottom)
				(hide yes)
			)
		)
		(property "Datasheet" "https://www.kingbrightusa.com/images/catalog/SPEC/APTF1616SURKCGKSYKC.pdf"
			(at 256.54 167.64 0)
			(effects
				(font
					(size 1.27 1.27)
					(thickness 0.15)
				)
				(justify left bottom)
				(hide yes)
			)
		)
		(property "Description" ""
			(at 226.06 154.94 0)
			(effects
				(font
					(size 1.27 1.27)
				)
				(hide yes)
			)
		)
		(property "MPN" "APTF1616SURKCGKSYKC"
			(at 235.585 142.24 0)
			(effects
				(font
					(size 1.27 1.27)
					(thickness 0.15)
				)
			)
		)
		(property "Manufacturer" "Kingbright"
			(at 256.54 172.72 0)
			(effects
				(font
					(size 1.27 1.27)
					(thickness 0.15)
				)
				(justify left bottom)
				(hide yes)
			)
		)
		(property "Color" "R, G, Y"
			(at 235.585 144.78 0)
			(effects
				(font
					(size 1.27 1.27)
				)
			)
		)
		(property "Author" "Antmicro"
			(at 256.54 175.26 0)
			(effects
				(font
					(size 1.27 1.27)
					(thickness 0.15)
				)
				(justify left bottom)
				(hide yes)
			)
		)
		(property "License" "Apache-2.0"
			(at 256.54 177.8 0)
			(effects
				(font
					(size 1.27 1.27)
					(thickness 0.15)
				)
				(justify left bottom)
				(hide yes)
			)
		)
		(pin "4"
		)
		(pin "2"
		)
		(pin "3"
		)
		(pin "1"
		)
		(instances
			(project "data-center-rdimm-ddr5-tester"
				(path ""
					(reference "D20")
					(unit 1)
				)
			)
		)
	)
	(symbol
		(lib_id "antmicropower:GND")
		(at 288.29 204.47 0)
		(unit 1)
		(exclude_from_sim no)
		(in_bom yes)
		(on_board yes)
		(dnp no)
		(fields_autoplaced yes)
		(property "Reference" "#PWR0205"
			(at 288.29 210.82 0)
			(effects
				(font
					(size 1.27 1.27)
				)
				(hide yes)
			)
		)
		(property "Value" "GND"
			(at 286.385 208.915 0)
			(effects
				(font
					(size 1.27 1.27)
					(thickness 0.15)
				)
				(justify left bottom)
			)
		)
		(property "Footprint" ""
			(at 297.18 212.09 0)
			(effects
				(font
					(size 1.27 1.27)
					(thickness 0.15)
				)
				(justify left bottom)
				(hide yes)
			)
		)
		(property "Datasheet" ""
			(at 297.18 217.17 0)
			(effects
				(font
					(size 1.27 1.27)
					(thickness 0.15)
				)
				(justify left bottom)
				(hide yes)
			)
		)
		(property "Description" ""
			(at 288.29 204.47 0)
			(effects
				(font
					(size 1.27 1.27)
				)
				(hide yes)
			)
		)
		(property "Author" "Antmicro"
			(at 297.18 209.55 0)
			(effects
				(font
					(size 1.27 1.27)
					(thickness 0.15)
				)
				(justify left bottom)
				(hide yes)
			)
		)
		(property "License" "Apache-2.0"
			(at 297.18 212.09 0)
			(effects
				(font
					(size 1.27 1.27)
					(thickness 0.15)
				)
				(justify left bottom)
				(hide yes)
			)
		)
		(pin "1"
		)
		(instances
			(project "data-center-rdimm-ddr5-tester"
				(path ""
					(reference "#PWR0205")
					(unit 1)
				)
			)
		)
	)
	(symbol
		(lib_id "antmicroCapacitors0402:C_100n_0402")
		(at 374.65 238.76 90)
		(unit 1)
		(exclude_from_sim no)
		(in_bom yes)
		(on_board yes)
		(dnp no)
		(fields_autoplaced yes)
		(property "Reference" "C10"
			(at 376.9741 235.383 90)
			(effects
				(font
					(size 1.27 1.27)
					(thickness 0.15)
				)
				(justify right)
			)
		)
		(property "Value" "C_100n_0402"
			(at 384.81 218.44 0)
			(effects
				(font
					(size 1.27 1.27)
					(thickness 0.15)
				)
				(justify left bottom)
				(hide yes)
			)
		)
		(property "Footprint" "antmicro-footprints:C_0402_1005Metric"
			(at 387.35 218.44 0)
			(effects
				(font
					(size 1.27 1.27)
					(thickness 0.15)
				)
				(justify left bottom)
				(hide yes)
			)
		)
		(property "Datasheet" "https://www.murata.com/products/productdetail?partno=GRM155R61H104KE14%23"
			(at 389.89 218.44 0)
			(effects
				(font
					(size 1.27 1.27)
					(thickness 0.15)
				)
				(justify left bottom)
				(hide yes)
			)
		)
		(property "Description" ""
			(at 374.65 238.76 0)
			(effects
				(font
					(size 1.27 1.27)
				)
				(hide yes)
			)
		)
		(property "MPN" "GRM155R61H104KE14D"
			(at 392.43 218.44 0)
			(effects
				(font
					(size 1.27 1.27)
					(thickness 0.15)
				)
				(justify left bottom)
				(hide yes)
			)
		)
		(property "Manufacturer" "Murata"
			(at 394.97 218.44 0)
			(effects
				(font
					(size 1.27 1.27)
					(thickness 0.15)
				)
				(justify left bottom)
				(hide yes)
			)
		)
		(property "License" "Apache-2.0"
			(at 397.51 218.44 0)
			(effects
				(font
					(size 1.27 1.27)
					(thickness 0.15)
				)
				(justify left bottom)
				(hide yes)
			)
		)
		(property "Author" "Antmicro"
			(at 400.05 218.44 0)
			(effects
				(font
					(size 1.27 1.27)
					(thickness 0.15)
				)
				(justify left bottom)
				(hide yes)
			)
		)
		(property "Val" "100n"
			(at 376.9741 237.9067 90)
			(effects
				(font
					(size 1.27 1.27)
					(thickness 0.15)
				)
				(justify right)
			)
		)
		(property "Voltage" "50V"
			(at 402.59 218.44 0)
			(effects
				(font
					(size 1.27 1.27)
				)
				(justify left bottom)
				(hide yes)
			)
		)
		(property "Dielectric" "X5R"
			(at 405.13 218.44 0)
			(effects
				(font
					(size 1.27 1.27)
				)
				(justify left bottom)
				(hide yes)
			)
		)
		(pin "1"
		)
		(pin "2"
		)
		(instances
			(project "data-center-rdimm-ddr5-tester"
				(path ""
					(reference "C10")
					(unit 1)
				)
			)
		)
	)
	(symbol
		(lib_id "antmicropower:GND")
		(at 271.78 100.33 0)
		(unit 1)
		(exclude_from_sim no)
		(in_bom yes)
		(on_board yes)
		(dnp no)
		(fields_autoplaced yes)
		(property "Reference" "#PWR036"
			(at 271.78 106.68 0)
			(effects
				(font
					(size 1.27 1.27)
				)
				(hide yes)
			)
		)
		(property "Value" "GND"
			(at 269.875 104.775 0)
			(effects
				(font
					(size 1.27 1.27)
					(thickness 0.15)
				)
				(justify left bottom)
			)
		)
		(property "Footprint" ""
			(at 280.67 107.95 0)
			(effects
				(font
					(size 1.27 1.27)
					(thickness 0.15)
				)
				(justify left bottom)
				(hide yes)
			)
		)
		(property "Datasheet" ""
			(at 280.67 113.03 0)
			(effects
				(font
					(size 1.27 1.27)
					(thickness 0.15)
				)
				(justify left bottom)
				(hide yes)
			)
		)
		(property "Description" ""
			(at 271.78 100.33 0)
			(effects
				(font
					(size 1.27 1.27)
				)
				(hide yes)
			)
		)
		(property "Author" "Antmicro"
			(at 280.67 105.41 0)
			(effects
				(font
					(size 1.27 1.27)
					(thickness 0.15)
				)
				(justify left bottom)
				(hide yes)
			)
		)
		(property "License" "Apache-2.0"
			(at 280.67 107.95 0)
			(effects
				(font
					(size 1.27 1.27)
					(thickness 0.15)
				)
				(justify left bottom)
				(hide yes)
			)
		)
		(pin "1"
		)
		(instances
			(project "data-center-rdimm-ddr5-tester"
				(path ""
					(reference "#PWR036")
					(unit 1)
				)
			)
		)
	)
)
